(kicad_sch
	(version 20231120)
	(generator "eeschema")
	(generator_version "8.0")
	(paper "A3")
	(title_block
		(title "Jetson Orin Baseboard")
		(date "2025-03-12")
		(rev "1.3.4")
		(company "Antmicro Ltd")
		(comment 1 "www.antmicro.com")
	)
	(junction
		(at 101.6 213.36)
		(diameter 0)
		(color 0 0 0 0)
	)
	(junction
		(at 339.09 190.5)
		(diameter 0)
		(color 0 0 0 0)
	)
	(junction
		(at 210.82 182.88)
		(diameter 0)
		(color 0 0 0 0)
	)
	(junction
		(at 210.82 86.36)
		(diameter 0)
		(color 0 0 0 0)
	)
	(junction
		(at 209.55 73.66)
		(diameter 0)
		(color 0 0 0 0)
	)
	(junction
		(at 101.6 182.88)
		(diameter 0)
		(color 0 0 0 0)
	)
	(junction
		(at 179.07 182.88)
		(diameter 0)
		(color 0 0 0 0)
	)
	(junction
		(at 349.25 182.88)
		(diameter 0)
		(color 0 0 0 0)
	)
	(junction
		(at 339.09 182.88)
		(diameter 0)
		(color 0 0 0 0)
	)
	(junction
		(at 96.52 213.36)
		(diameter 0)
		(color 0 0 0 0)
	)
	(junction
		(at 231.14 182.88)
		(diameter 0)
		(color 0 0 0 0)
	)
	(junction
		(at 96.52 182.88)
		(diameter 0)
		(color 0 0 0 0)
	)
	(junction
		(at 200.66 182.88)
		(diameter 0)
		(color 0 0 0 0)
	)
	(junction
		(at 137.16 182.88)
		(diameter 0)
		(color 0 0 0 0)
	)
	(junction
		(at 241.3 182.88)
		(diameter 0)
		(color 0 0 0 0)
	)
	(junction
		(at 107.95 213.36)
		(diameter 0)
		(color 0 0 0 0)
	)
	(junction
		(at 124.46 213.36)
		(diameter 0)
		(color 0 0 0 0)
	)
	(junction
		(at 107.95 218.44)
		(diameter 0)
		(color 0 0 0 0)
	)
	(junction
		(at 328.93 198.12)
		(diameter 0)
		(color 0 0 0 0)
	)
	(junction
		(at 162.56 226.06)
		(diameter 0)
		(color 0 0 0 0)
	)
	(junction
		(at 257.81 182.88)
		(diameter 0)
		(color 0 0 0 0)
	)
	(junction
		(at 72.39 182.88)
		(diameter 0)
		(color 0 0 0 0)
	)
	(junction
		(at 359.41 182.88)
		(diameter 0)
		(color 0 0 0 0)
	)
	(junction
		(at 220.98 182.88)
		(diameter 0)
		(color 0 0 0 0)
	)
	(junction
		(at 137.16 213.36)
		(diameter 0)
		(color 0 0 0 0)
	)
	(junction
		(at 127 213.36)
		(diameter 0)
		(color 0 0 0 0)
	)
	(junction
		(at 52.07 203.2)
		(diameter 0)
		(color 0 0 0 0)
	)
	(junction
		(at 328.93 182.88)
		(diameter 0)
		(color 0 0 0 0)
	)
	(junction
		(at 369.57 182.88)
		(diameter 0)
		(color 0 0 0 0)
	)
	(junction
		(at 297.18 194.31)
		(diameter 0)
		(color 0 0 0 0)
	)
	(junction
		(at 297.18 182.88)
		(diameter 0)
		(color 0 0 0 0)
	)
	(junction
		(at 107.95 215.9)
		(diameter 0)
		(color 0 0 0 0)
	)
	(junction
		(at 257.81 207.01)
		(diameter 0)
		(color 0 0 0 0)
	)
	(junction
		(at 257.81 194.31)
		(diameter 0)
		(color 0 0 0 0)
	)
	(junction
		(at 133.35 182.88)
		(diameter 0)
		(color 0 0 0 0)
	)
	(junction
		(at 184.15 73.66)
		(diameter 0)
		(color 0 0 0 0)
	)
	(junction
		(at 137.16 210.82)
		(diameter 0)
		(color 0 0 0 0)
	)
	(junction
		(at 274.32 194.31)
		(diameter 0)
		(color 0 0 0 0)
	)
	(junction
		(at 168.91 182.88)
		(diameter 0)
		(color 0 0 0 0)
	)
	(junction
		(at 187.96 182.88)
		(diameter 0)
		(color 0 0 0 0)
	)
	(no_connect
		(at 160.02 218.44)
	)
	(no_connect
		(at 138.43 226.06)
	)
	(wire
		(pts
			(xy 207.01 76.2) (xy 218.44 76.2)
		)
		(stroke
			(width 0)
			(type default)
		)
	)
	(wire
		(pts
			(xy 53.34 182.88) (xy 52.07 182.88)
		)
		(stroke
			(width 0)
			(type default)
		)
	)
	(wire
		(pts
			(xy 166.37 55.88) (xy 185.42 55.88)
		)
		(stroke
			(width 0)
			(type default)
		)
	)
	(wire
		(pts
			(xy 137.16 210.82) (xy 138.43 210.82)
		)
		(stroke
			(width 0)
			(type default)
		)
	)
	(wire
		(pts
			(xy 327.66 182.88) (xy 328.93 182.88)
		)
		(stroke
			(width 0)
			(type default)
		)
	)
	(wire
		(pts
			(xy 313.69 236.22) (xy 313.69 237.49)
		)
		(stroke
			(width 0)
			(type default)
		)
	)
	(wire
		(pts
			(xy 107.95 220.98) (xy 107.95 218.44)
		)
		(stroke
			(width 0)
			(type default)
		)
	)
	(wire
		(pts
			(xy 306.07 190.5) (xy 307.34 190.5)
		)
		(stroke
			(width 0)
			(type default)
		)
	)
	(wire
		(pts
			(xy 207.01 73.66) (xy 209.55 73.66)
		)
		(stroke
			(width 0)
			(type default)
		)
	)
	(wire
		(pts
			(xy 52.07 203.2) (xy 53.34 203.2)
		)
		(stroke
			(width 0)
			(type default)
		)
	)
	(wire
		(pts
			(xy 220.98 182.88) (xy 220.98 199.39)
		)
		(stroke
			(width 0)
			(type default)
		)
	)
	(wire
		(pts
			(xy 241.3 190.5) (xy 241.3 210.82)
		)
		(stroke
			(width 0)
			(type default)
		)
	)
	(wire
		(pts
			(xy 210.82 87.63) (xy 210.82 86.36)
		)
		(stroke
			(width 0)
			(type default)
		)
	)
	(wire
		(pts
			(xy 327.66 185.42) (xy 328.93 185.42)
		)
		(stroke
			(width 0)
			(type default)
		)
	)
	(wire
		(pts
			(xy 241.3 182.88) (xy 257.81 182.88)
		)
		(stroke
			(width 0)
			(type default)
		)
	)
	(wire
		(pts
			(xy 52.07 203.2) (xy 52.07 213.36)
		)
		(stroke
			(width 0)
			(type default)
		)
	)
	(wire
		(pts
			(xy 137.16 193.04) (xy 138.43 193.04)
		)
		(stroke
			(width 0)
			(type default)
		)
	)
	(wire
		(pts
			(xy 241.3 182.88) (xy 241.3 185.42)
		)
		(stroke
			(width 0)
			(type default)
		)
	)
	(wire
		(pts
			(xy 168.91 182.88) (xy 168.91 184.15)
		)
		(stroke
			(width 0)
			(type default)
		)
	)
	(wire
		(pts
			(xy 274.32 199.39) (xy 274.32 194.31)
		)
		(stroke
			(width 0)
			(type default)
		)
	)
	(wire
		(pts
			(xy 118.11 218.44) (xy 138.43 218.44)
		)
		(stroke
			(width 0)
			(type default)
		)
	)
	(wire
		(pts
			(xy 359.41 182.88) (xy 359.41 187.96)
		)
		(stroke
			(width 0)
			(type default)
		)
	)
	(wire
		(pts
			(xy 160.02 198.12) (xy 187.96 198.12)
		)
		(stroke
			(width 0)
			(type default)
		)
	)
	(wire
		(pts
			(xy 185.42 83.82) (xy 152.4 83.82)
		)
		(stroke
			(width 0)
			(type default)
		)
	)
	(wire
		(pts
			(xy 339.09 182.88) (xy 339.09 184.15)
		)
		(stroke
			(width 0)
			(type default)
		)
	)
	(wire
		(pts
			(xy 257.81 215.9) (xy 257.81 218.44)
		)
		(stroke
			(width 0)
			(type default)
		)
	)
	(wire
		(pts
			(xy 278.13 236.22) (xy 285.75 236.22)
		)
		(stroke
			(width 0)
			(type default)
		)
	)
	(wire
		(pts
			(xy 71.12 182.88) (xy 72.39 182.88)
		)
		(stroke
			(width 0)
			(type default)
		)
	)
	(wire
		(pts
			(xy 328.93 185.42) (xy 328.93 182.88)
		)
		(stroke
			(width 0)
			(type default)
		)
	)
	(wire
		(pts
			(xy 210.82 204.47) (xy 210.82 218.44)
		)
		(stroke
			(width 0)
			(type default)
		)
	)
	(wire
		(pts
			(xy 297.18 190.5) (xy 297.18 194.31)
		)
		(stroke
			(width 0)
			(type default)
		)
	)
	(wire
		(pts
			(xy 41.91 208.28) (xy 53.34 208.28)
		)
		(stroke
			(width 0)
			(type default)
		)
	)
	(wire
		(pts
			(xy 152.4 78.74) (xy 185.42 78.74)
		)
		(stroke
			(width 0)
			(type default)
		)
	)
	(wire
		(pts
			(xy 162.56 223.52) (xy 162.56 226.06)
		)
		(stroke
			(width 0)
			(type default)
		)
	)
	(wire
		(pts
			(xy 96.52 213.36) (xy 96.52 215.9)
		)
		(stroke
			(width 0)
			(type default)
		)
	)
	(wire
		(pts
			(xy 160.02 193.04) (xy 168.91 193.04)
		)
		(stroke
			(width 0)
			(type default)
		)
	)
	(wire
		(pts
			(xy 220.98 86.36) (xy 210.82 86.36)
		)
		(stroke
			(width 0)
			(type default)
		)
	)
	(wire
		(pts
			(xy 231.14 182.88) (xy 241.3 182.88)
		)
		(stroke
			(width 0)
			(type default)
		)
	)
	(wire
		(pts
			(xy 209.55 73.66) (xy 209.55 78.74)
		)
		(stroke
			(width 0)
			(type default)
		)
	)
	(wire
		(pts
			(xy 72.39 182.88) (xy 72.39 203.2)
		)
		(stroke
			(width 0)
			(type default)
		)
	)
	(wire
		(pts
			(xy 369.57 182.88) (xy 377.19 182.88)
		)
		(stroke
			(width 0)
			(type default)
		)
	)
	(wire
		(pts
			(xy 328.93 195.58) (xy 328.93 198.12)
		)
		(stroke
			(width 0)
			(type default)
		)
	)
	(wire
		(pts
			(xy 306.07 194.31) (xy 306.07 190.5)
		)
		(stroke
			(width 0)
			(type default)
		)
	)
	(wire
		(pts
			(xy 339.09 190.5) (xy 339.09 191.77)
		)
		(stroke
			(width 0)
			(type default)
		)
	)
	(wire
		(pts
			(xy 127 203.2) (xy 138.43 203.2)
		)
		(stroke
			(width 0)
			(type default)
		)
	)
	(wire
		(pts
			(xy 113.03 215.9) (xy 107.95 215.9)
		)
		(stroke
			(width 0)
			(type default)
		)
	)
	(wire
		(pts
			(xy 179.07 182.88) (xy 187.96 182.88)
		)
		(stroke
			(width 0)
			(type default)
		)
	)
	(wire
		(pts
			(xy 166.37 63.5) (xy 185.42 63.5)
		)
		(stroke
			(width 0)
			(type default)
		)
	)
	(wire
		(pts
			(xy 257.81 190.5) (xy 257.81 194.31)
		)
		(stroke
			(width 0)
			(type default)
		)
	)
	(wire
		(pts
			(xy 118.11 215.9) (xy 138.43 215.9)
		)
		(stroke
			(width 0)
			(type default)
		)
	)
	(wire
		(pts
			(xy 200.66 204.47) (xy 200.66 218.44)
		)
		(stroke
			(width 0)
			(type default)
		)
	)
	(wire
		(pts
			(xy 72.39 182.88) (xy 83.82 182.88)
		)
		(stroke
			(width 0)
			(type default)
		)
	)
	(wire
		(pts
			(xy 267.97 236.22) (xy 273.05 236.22)
		)
		(stroke
			(width 0)
			(type default)
		)
	)
	(wire
		(pts
			(xy 210.82 182.88) (xy 210.82 199.39)
		)
		(stroke
			(width 0)
			(type default)
		)
	)
	(wire
		(pts
			(xy 107.95 215.9) (xy 107.95 218.44)
		)
		(stroke
			(width 0)
			(type default)
		)
	)
	(wire
		(pts
			(xy 297.18 203.2) (xy 297.18 217.17)
		)
		(stroke
			(width 0)
			(type default)
		)
	)
	(wire
		(pts
			(xy 207.01 78.74) (xy 209.55 78.74)
		)
		(stroke
			(width 0)
			(type default)
		)
	)
	(wire
		(pts
			(xy 297.18 182.88) (xy 307.34 182.88)
		)
		(stroke
			(width 0)
			(type default)
		)
	)
	(wire
		(pts
			(xy 160.02 195.58) (xy 179.07 195.58)
		)
		(stroke
			(width 0)
			(type default)
		)
	)
	(wire
		(pts
			(xy 179.07 189.23) (xy 179.07 195.58)
		)
		(stroke
			(width 0)
			(type default)
		)
	)
	(wire
		(pts
			(xy 162.56 226.06) (xy 160.02 226.06)
		)
		(stroke
			(width 0)
			(type default)
		)
	)
	(wire
		(pts
			(xy 166.37 68.58) (xy 185.42 68.58)
		)
		(stroke
			(width 0)
			(type default)
		)
	)
	(wire
		(pts
			(xy 133.35 195.58) (xy 138.43 195.58)
		)
		(stroke
			(width 0)
			(type default)
		)
	)
	(wire
		(pts
			(xy 96.52 182.88) (xy 96.52 195.58)
		)
		(stroke
			(width 0)
			(type default)
		)
	)
	(wire
		(pts
			(xy 285.75 232.41) (xy 267.97 232.41)
		)
		(stroke
			(width 0)
			(type default)
		)
	)
	(wire
		(pts
			(xy 41.91 198.12) (xy 53.34 198.12)
		)
		(stroke
			(width 0)
			(type default)
		)
	)
	(wire
		(pts
			(xy 207.01 81.28) (xy 218.44 81.28)
		)
		(stroke
			(width 0)
			(type default)
		)
	)
	(wire
		(pts
			(xy 137.16 182.88) (xy 168.91 182.88)
		)
		(stroke
			(width 0)
			(type default)
		)
	)
	(wire
		(pts
			(xy 298.45 232.41) (xy 299.72 232.41)
		)
		(stroke
			(width 0)
			(type default)
		)
	)
	(wire
		(pts
			(xy 52.07 182.88) (xy 52.07 203.2)
		)
		(stroke
			(width 0)
			(type default)
		)
	)
	(wire
		(pts
			(xy 210.82 182.88) (xy 220.98 182.88)
		)
		(stroke
			(width 0)
			(type default)
		)
	)
	(wire
		(pts
			(xy 168.91 182.88) (xy 179.07 182.88)
		)
		(stroke
			(width 0)
			(type default)
		)
	)
	(wire
		(pts
			(xy 101.6 213.36) (xy 107.95 213.36)
		)
		(stroke
			(width 0)
			(type default)
		)
	)
	(wire
		(pts
			(xy 220.98 204.47) (xy 220.98 218.44)
		)
		(stroke
			(width 0)
			(type default)
		)
	)
	(wire
		(pts
			(xy 257.81 194.31) (xy 257.81 207.01)
		)
		(stroke
			(width 0)
			(type default)
		)
	)
	(wire
		(pts
			(xy 223.52 76.2) (xy 231.14 76.2)
		)
		(stroke
			(width 0)
			(type default)
		)
	)
	(wire
		(pts
			(xy 96.52 213.36) (xy 101.6 213.36)
		)
		(stroke
			(width 0)
			(type default)
		)
	)
	(wire
		(pts
			(xy 118.11 220.98) (xy 138.43 220.98)
		)
		(stroke
			(width 0)
			(type default)
		)
	)
	(wire
		(pts
			(xy 257.81 194.31) (xy 262.89 194.31)
		)
		(stroke
			(width 0)
			(type default)
		)
	)
	(wire
		(pts
			(xy 101.6 180.34) (xy 101.6 182.88)
		)
		(stroke
			(width 0)
			(type default)
		)
	)
	(wire
		(pts
			(xy 187.96 189.23) (xy 187.96 198.12)
		)
		(stroke
			(width 0)
			(type default)
		)
	)
	(wire
		(pts
			(xy 257.81 182.88) (xy 297.18 182.88)
		)
		(stroke
			(width 0)
			(type default)
		)
	)
	(wire
		(pts
			(xy 96.52 200.66) (xy 96.52 213.36)
		)
		(stroke
			(width 0)
			(type default)
		)
	)
	(wire
		(pts
			(xy 274.32 194.31) (xy 297.18 194.31)
		)
		(stroke
			(width 0)
			(type default)
		)
	)
	(wire
		(pts
			(xy 137.16 213.36) (xy 138.43 213.36)
		)
		(stroke
			(width 0)
			(type default)
		)
	)
	(wire
		(pts
			(xy 179.07 73.66) (xy 179.07 87.63)
		)
		(stroke
			(width 0)
			(type default)
		)
	)
	(wire
		(pts
			(xy 184.15 76.2) (xy 185.42 76.2)
		)
		(stroke
			(width 0)
			(type default)
		)
	)
	(wire
		(pts
			(xy 359.41 193.04) (xy 359.41 199.39)
		)
		(stroke
			(width 0)
			(type default)
		)
	)
	(wire
		(pts
			(xy 179.07 92.71) (xy 179.07 93.98)
		)
		(stroke
			(width 0)
			(type default)
		)
	)
	(wire
		(pts
			(xy 187.96 182.88) (xy 187.96 184.15)
		)
		(stroke
			(width 0)
			(type default)
		)
	)
	(wire
		(pts
			(xy 166.37 66.04) (xy 185.42 66.04)
		)
		(stroke
			(width 0)
			(type default)
		)
	)
	(wire
		(pts
			(xy 185.42 73.66) (xy 184.15 73.66)
		)
		(stroke
			(width 0)
			(type default)
		)
	)
	(wire
		(pts
			(xy 133.35 182.88) (xy 133.35 184.15)
		)
		(stroke
			(width 0)
			(type default)
		)
	)
	(wire
		(pts
			(xy 328.93 182.88) (xy 339.09 182.88)
		)
		(stroke
			(width 0)
			(type default)
		)
	)
	(wire
		(pts
			(xy 297.18 194.31) (xy 297.18 198.12)
		)
		(stroke
			(width 0)
			(type default)
		)
	)
	(wire
		(pts
			(xy 220.98 182.88) (xy 231.14 182.88)
		)
		(stroke
			(width 0)
			(type default)
		)
	)
	(wire
		(pts
			(xy 267.97 194.31) (xy 274.32 194.31)
		)
		(stroke
			(width 0)
			(type default)
		)
	)
	(wire
		(pts
			(xy 88.9 213.36) (xy 96.52 213.36)
		)
		(stroke
			(width 0)
			(type default)
		)
	)
	(wire
		(pts
			(xy 185.42 81.28) (xy 152.4 81.28)
		)
		(stroke
			(width 0)
			(type default)
		)
	)
	(wire
		(pts
			(xy 223.52 81.28) (xy 231.14 81.28)
		)
		(stroke
			(width 0)
			(type default)
		)
	)
	(wire
		(pts
			(xy 96.52 182.88) (xy 101.6 182.88)
		)
		(stroke
			(width 0)
			(type default)
		)
	)
	(wire
		(pts
			(xy 166.37 50.8) (xy 185.42 50.8)
		)
		(stroke
			(width 0)
			(type default)
		)
	)
	(wire
		(pts
			(xy 138.43 208.28) (xy 137.16 208.28)
		)
		(stroke
			(width 0)
			(type default)
		)
	)
	(wire
		(pts
			(xy 369.57 193.04) (xy 369.57 199.39)
		)
		(stroke
			(width 0)
			(type default)
		)
	)
	(wire
		(pts
			(xy 175.26 213.36) (xy 193.04 213.36)
		)
		(stroke
			(width 0)
			(type default)
		)
	)
	(wire
		(pts
			(xy 101.6 182.88) (xy 101.6 195.58)
		)
		(stroke
			(width 0)
			(type default)
		)
	)
	(wire
		(pts
			(xy 339.09 189.23) (xy 339.09 190.5)
		)
		(stroke
			(width 0)
			(type default)
		)
	)
	(wire
		(pts
			(xy 231.14 204.47) (xy 231.14 218.44)
		)
		(stroke
			(width 0)
			(type default)
		)
	)
	(wire
		(pts
			(xy 327.66 198.12) (xy 328.93 198.12)
		)
		(stroke
			(width 0)
			(type default)
		)
	)
	(wire
		(pts
			(xy 101.6 182.88) (xy 133.35 182.88)
		)
		(stroke
			(width 0)
			(type default)
		)
	)
	(wire
		(pts
			(xy 88.9 182.88) (xy 96.52 182.88)
		)
		(stroke
			(width 0)
			(type default)
		)
	)
	(wire
		(pts
			(xy 306.07 198.12) (xy 307.34 198.12)
		)
		(stroke
			(width 0)
			(type default)
		)
	)
	(wire
		(pts
			(xy 267.97 236.22) (xy 267.97 237.49)
		)
		(stroke
			(width 0)
			(type default)
		)
	)
	(wire
		(pts
			(xy 137.16 210.82) (xy 137.16 213.36)
		)
		(stroke
			(width 0)
			(type default)
		)
	)
	(wire
		(pts
			(xy 200.66 182.88) (xy 210.82 182.88)
		)
		(stroke
			(width 0)
			(type default)
		)
	)
	(wire
		(pts
			(xy 133.35 189.23) (xy 133.35 195.58)
		)
		(stroke
			(width 0)
			(type default)
		)
	)
	(wire
		(pts
			(xy 349.25 182.88) (xy 349.25 187.96)
		)
		(stroke
			(width 0)
			(type default)
		)
	)
	(wire
		(pts
			(xy 168.91 189.23) (xy 168.91 193.04)
		)
		(stroke
			(width 0)
			(type default)
		)
	)
	(wire
		(pts
			(xy 184.15 73.66) (xy 184.15 76.2)
		)
		(stroke
			(width 0)
			(type default)
		)
	)
	(wire
		(pts
			(xy 107.95 213.36) (xy 107.95 215.9)
		)
		(stroke
			(width 0)
			(type default)
		)
	)
	(wire
		(pts
			(xy 200.66 182.88) (xy 200.66 199.39)
		)
		(stroke
			(width 0)
			(type default)
		)
	)
	(wire
		(pts
			(xy 52.07 213.36) (xy 83.82 213.36)
		)
		(stroke
			(width 0)
			(type default)
		)
	)
	(wire
		(pts
			(xy 349.25 193.04) (xy 349.25 199.39)
		)
		(stroke
			(width 0)
			(type default)
		)
	)
	(wire
		(pts
			(xy 349.25 182.88) (xy 359.41 182.88)
		)
		(stroke
			(width 0)
			(type default)
		)
	)
	(wire
		(pts
			(xy 107.95 213.36) (xy 124.46 213.36)
		)
		(stroke
			(width 0)
			(type default)
		)
	)
	(wire
		(pts
			(xy 160.02 223.52) (xy 162.56 223.52)
		)
		(stroke
			(width 0)
			(type default)
		)
	)
	(wire
		(pts
			(xy 308.61 236.22) (xy 313.69 236.22)
		)
		(stroke
			(width 0)
			(type default)
		)
	)
	(wire
		(pts
			(xy 220.98 87.63) (xy 220.98 86.36)
		)
		(stroke
			(width 0)
			(type default)
		)
	)
	(wire
		(pts
			(xy 179.07 182.88) (xy 179.07 184.15)
		)
		(stroke
			(width 0)
			(type default)
		)
	)
	(wire
		(pts
			(xy 124.46 209.55) (xy 124.46 213.36)
		)
		(stroke
			(width 0)
			(type default)
		)
	)
	(wire
		(pts
			(xy 241.3 215.9) (xy 241.3 218.44)
		)
		(stroke
			(width 0)
			(type default)
		)
	)
	(wire
		(pts
			(xy 209.55 72.39) (xy 209.55 73.66)
		)
		(stroke
			(width 0)
			(type default)
		)
	)
	(wire
		(pts
			(xy 166.37 60.96) (xy 185.42 60.96)
		)
		(stroke
			(width 0)
			(type default)
		)
	)
	(wire
		(pts
			(xy 162.56 228.6) (xy 162.56 226.06)
		)
		(stroke
			(width 0)
			(type default)
		)
	)
	(wire
		(pts
			(xy 72.39 203.2) (xy 71.12 203.2)
		)
		(stroke
			(width 0)
			(type default)
		)
	)
	(wire
		(pts
			(xy 274.32 209.55) (xy 274.32 217.17)
		)
		(stroke
			(width 0)
			(type default)
		)
	)
	(wire
		(pts
			(xy 166.37 58.42) (xy 185.42 58.42)
		)
		(stroke
			(width 0)
			(type default)
		)
	)
	(wire
		(pts
			(xy 306.07 198.12) (xy 306.07 217.17)
		)
		(stroke
			(width 0)
			(type default)
		)
	)
	(wire
		(pts
			(xy 127 209.55) (xy 127 213.36)
		)
		(stroke
			(width 0)
			(type default)
		)
	)
	(wire
		(pts
			(xy 166.37 53.34) (xy 185.42 53.34)
		)
		(stroke
			(width 0)
			(type default)
		)
	)
	(wire
		(pts
			(xy 137.16 208.28) (xy 137.16 210.82)
		)
		(stroke
			(width 0)
			(type default)
		)
	)
	(wire
		(pts
			(xy 339.09 182.88) (xy 349.25 182.88)
		)
		(stroke
			(width 0)
			(type default)
		)
	)
	(wire
		(pts
			(xy 231.14 182.88) (xy 231.14 199.39)
		)
		(stroke
			(width 0)
			(type default)
		)
	)
	(wire
		(pts
			(xy 297.18 194.31) (xy 306.07 194.31)
		)
		(stroke
			(width 0)
			(type default)
		)
	)
	(wire
		(pts
			(xy 187.96 182.88) (xy 200.66 182.88)
		)
		(stroke
			(width 0)
			(type default)
		)
	)
	(wire
		(pts
			(xy 328.93 198.12) (xy 328.93 199.39)
		)
		(stroke
			(width 0)
			(type default)
		)
	)
	(wire
		(pts
			(xy 210.82 92.71) (xy 210.82 93.98)
		)
		(stroke
			(width 0)
			(type default)
		)
	)
	(wire
		(pts
			(xy 127 203.2) (xy 127 204.47)
		)
		(stroke
			(width 0)
			(type default)
		)
	)
	(wire
		(pts
			(xy 327.66 190.5) (xy 339.09 190.5)
		)
		(stroke
			(width 0)
			(type default)
		)
	)
	(wire
		(pts
			(xy 220.98 92.71) (xy 220.98 93.98)
		)
		(stroke
			(width 0)
			(type default)
		)
	)
	(wire
		(pts
			(xy 245.11 207.01) (xy 257.81 207.01)
		)
		(stroke
			(width 0)
			(type default)
		)
	)
	(wire
		(pts
			(xy 124.46 213.36) (xy 127 213.36)
		)
		(stroke
			(width 0)
			(type default)
		)
	)
	(wire
		(pts
			(xy 327.66 195.58) (xy 328.93 195.58)
		)
		(stroke
			(width 0)
			(type default)
		)
	)
	(wire
		(pts
			(xy 339.09 199.39) (xy 339.09 196.85)
		)
		(stroke
			(width 0)
			(type default)
		)
	)
	(wire
		(pts
			(xy 257.81 207.01) (xy 267.97 207.01)
		)
		(stroke
			(width 0)
			(type default)
		)
	)
	(wire
		(pts
			(xy 41.91 187.96) (xy 53.34 187.96)
		)
		(stroke
			(width 0)
			(type default)
		)
	)
	(wire
		(pts
			(xy 113.03 218.44) (xy 107.95 218.44)
		)
		(stroke
			(width 0)
			(type default)
		)
	)
	(wire
		(pts
			(xy 257.81 182.88) (xy 257.81 185.42)
		)
		(stroke
			(width 0)
			(type default)
		)
	)
	(wire
		(pts
			(xy 107.95 220.98) (xy 113.03 220.98)
		)
		(stroke
			(width 0)
			(type default)
		)
	)
	(wire
		(pts
			(xy 185.42 86.36) (xy 152.4 86.36)
		)
		(stroke
			(width 0)
			(type default)
		)
	)
	(polyline
		(pts
			(xy 12.7 134.62) (xy 407.67 134.62)
		)
		(stroke
			(width 0)
			(type default)
		)
	)
	(wire
		(pts
			(xy 41.91 177.8) (xy 53.34 177.8)
		)
		(stroke
			(width 0)
			(type default)
		)
	)
	(wire
		(pts
			(xy 179.07 73.66) (xy 184.15 73.66)
		)
		(stroke
			(width 0)
			(type default)
		)
	)
	(wire
		(pts
			(xy 101.6 200.66) (xy 101.6 213.36)
		)
		(stroke
			(width 0)
			(type default)
		)
	)
	(wire
		(pts
			(xy 369.57 182.88) (xy 369.57 187.96)
		)
		(stroke
			(width 0)
			(type default)
		)
	)
	(wire
		(pts
			(xy 133.35 182.88) (xy 137.16 182.88)
		)
		(stroke
			(width 0)
			(type default)
		)
	)
	(wire
		(pts
			(xy 137.16 182.88) (xy 137.16 193.04)
		)
		(stroke
			(width 0)
			(type default)
		)
	)
	(wire
		(pts
			(xy 297.18 182.88) (xy 297.18 185.42)
		)
		(stroke
			(width 0)
			(type default)
		)
	)
	(wire
		(pts
			(xy 257.81 207.01) (xy 257.81 210.82)
		)
		(stroke
			(width 0)
			(type default)
		)
	)
	(wire
		(pts
			(xy 127 213.36) (xy 137.16 213.36)
		)
		(stroke
			(width 0)
			(type default)
		)
	)
	(wire
		(pts
			(xy 160.02 213.36) (xy 170.18 213.36)
		)
		(stroke
			(width 0)
			(type default)
		)
	)
	(wire
		(pts
			(xy 359.41 182.88) (xy 369.57 182.88)
		)
		(stroke
			(width 0)
			(type default)
		)
	)
	(wire
		(pts
			(xy 298.45 236.22) (xy 303.53 236.22)
		)
		(stroke
			(width 0)
			(type default)
		)
	)
	(wire
		(pts
			(xy 207.01 86.36) (xy 210.82 86.36)
		)
		(stroke
			(width 0)
			(type default)
		)
	)
	(wire
		(pts
			(xy 124.46 200.66) (xy 138.43 200.66)
		)
		(stroke
			(width 0)
			(type default)
		)
	)
	(wire
		(pts
			(xy 124.46 200.66) (xy 124.46 204.47)
		)
		(stroke
			(width 0)
			(type default)
		)
	)
	(text "Power over Ethernet"
		(exclude_from_sim no)
		(at 168.91 143.51 0)
		(effects
			(font
				(size 4 4)
				(thickness 0.5994)
				(bold yes)
			)
			(justify left bottom)
		)
	)
	(text "Ethernet Connector"
		(exclude_from_sim no)
		(at 171.45 21.59 0)
		(effects
			(font
				(size 4 4)
				(thickness 0.5994)
				(bold yes)
			)
			(justify left bottom)
		)
	)
	(text "1/5.7 divider"
		(exclude_from_sim no)
		(at 290.83 181.61 0)
		(effects
			(font
				(size 1.27 1.27)
			)
			(justify left bottom)
		)
	)
	(text "Alternative MPNs: 6-2337992-8, TMJG4926HENL "
		(exclude_from_sim no)
		(at 197.104 103.124 0)
		(effects
			(font
				(size 1.27 1.27)
			)
		)
	)
	(label "REF"
		(at 137.16 218.44 180)
		(effects
			(font
				(size 1.27 1.27)
			)
			(justify right bottom)
		)
	)
	(label "TPL"
		(at 162.56 195.58 0)
		(effects
			(font
				(size 1.27 1.27)
			)
			(justify left bottom)
		)
	)
	(label "VDD"
		(at 102.87 182.88 0)
		(effects
			(font
				(size 1.27 1.27)
			)
			(justify left bottom)
		)
	)
	(label "VSS"
		(at 102.87 213.36 0)
		(effects
			(font
				(size 1.27 1.27)
			)
			(justify left bottom)
		)
	)
	(label "MPS_DUTY"
		(at 137.16 220.98 180)
		(effects
			(font
				(size 1.27 1.27)
			)
			(justify right bottom)
		)
	)
	(label "PAIR_910"
		(at 41.91 198.12 0)
		(effects
			(font
				(size 1.27 1.27)
			)
			(justify left bottom)
		)
	)
	(label "AMPS_CTL"
		(at 137.16 215.9 180)
		(effects
			(font
				(size 1.27 1.27)
			)
			(justify right bottom)
		)
	)
	(label "CLSB"
		(at 132.08 203.2 180)
		(effects
			(font
				(size 1.27 1.27)
			)
			(justify right bottom)
		)
	)
	(label "PAIR_910"
		(at 152.4 86.36 0)
		(effects
			(font
				(size 1.27 1.27)
			)
			(justify left bottom)
		)
	)
	(label "PAIR_78"
		(at 41.91 208.28 0)
		(effects
			(font
				(size 1.27 1.27)
			)
			(justify left bottom)
		)
	)
	(label "PAIR_12"
		(at 152.4 78.74 0)
		(effects
			(font
				(size 1.27 1.27)
			)
			(justify left bottom)
		)
	)
	(label "POE_ACTIVE"
		(at 267.97 232.41 0)
		(effects
			(font
				(size 1.27 1.27)
			)
			(justify left bottom)
		)
	)
	(label "DEN"
		(at 138.43 195.58 180)
		(effects
			(font
				(size 1.27 1.27)
			)
			(justify right bottom)
		)
	)
	(label "POE_ACTIVE"
		(at 245.11 207.01 0)
		(effects
			(font
				(size 1.27 1.27)
			)
			(justify left bottom)
		)
	)
	(label "PG"
		(at 163.83 213.36 180)
		(effects
			(font
				(size 1.27 1.27)
			)
			(justify right bottom)
		)
	)
	(label "~{BT}"
		(at 162.56 198.12 0)
		(effects
			(font
				(size 1.27 1.27)
			)
			(justify left bottom)
		)
	)
	(label "PAIR_36"
		(at 152.4 81.28 0)
		(effects
			(font
				(size 1.27 1.27)
			)
			(justify left bottom)
		)
	)
	(label "ULS-12_CTRL"
		(at 278.13 194.31 0)
		(effects
			(font
				(size 1.27 1.27)
			)
			(justify left bottom)
		)
	)
	(label "PAIR_36"
		(at 41.91 187.96 0)
		(effects
			(font
				(size 1.27 1.27)
			)
			(justify left bottom)
		)
	)
	(label "TPH"
		(at 162.56 193.04 0)
		(effects
			(font
				(size 1.27 1.27)
			)
			(justify left bottom)
		)
	)
	(label "PAIR_78"
		(at 152.4 83.82 0)
		(effects
			(font
				(size 1.27 1.27)
			)
			(justify left bottom)
		)
	)
	(label "CLSA"
		(at 127 200.66 0)
		(effects
			(font
				(size 1.27 1.27)
			)
			(justify left bottom)
		)
	)
	(label "POE_ACTIVE"
		(at 193.04 213.36 180)
		(effects
			(font
				(size 1.27 1.27)
			)
			(justify right bottom)
		)
	)
	(label "PAIR_12"
		(at 41.91 177.8 0)
		(effects
			(font
				(size 1.27 1.27)
			)
			(justify left bottom)
		)
	)
	(global_label "GBE_MDI3_N"
		(shape input)
		(at 166.37 68.58 180)
		(fields_autoplaced yes)
		(effects
			(font
				(size 1.27 1.27)
			)
			(justify right)
		)
		(property "Intersheetrefs" "${INTERSHEET_REFS}"
			(at 152.4664 68.5006 0)
			(effects
				(font
					(size 1.27 1.27)
				)
				(justify right)
			)
		)
	)
	(global_label "GBE_MDI3_P"
		(shape input)
		(at 166.37 66.04 180)
		(fields_autoplaced yes)
		(effects
			(font
				(size 1.27 1.27)
			)
			(justify right)
		)
		(property "Intersheetrefs" "${INTERSHEET_REFS}"
			(at 152.5269 65.9606 0)
			(effects
				(font
					(size 1.27 1.27)
				)
				(justify right)
			)
		)
	)
	(global_label "DISABLE_POE_DCDC"
		(shape input)
		(at 299.72 232.41 0)
		(fields_autoplaced yes)
		(effects
			(font
				(size 1.27 1.27)
			)
			(justify left)
		)
		(property "Intersheetrefs" "${INTERSHEET_REFS}"
			(at 320.5179 232.3306 0)
			(effects
				(font
					(size 1.27 1.27)
				)
				(justify left)
			)
		)
	)
	(global_label "GBE_MDI0_N"
		(shape input)
		(at 166.37 53.34 180)
		(fields_autoplaced yes)
		(effects
			(font
				(size 1.27 1.27)
			)
			(justify right)
		)
		(property "Intersheetrefs" "${INTERSHEET_REFS}"
			(at 152.4664 53.2606 0)
			(effects
				(font
					(size 1.27 1.27)
				)
				(justify right)
			)
		)
	)
	(global_label "GBE_LED_LINK"
		(shape input)
		(at 231.14 81.28 0)
		(fields_autoplaced yes)
		(effects
			(font
				(size 1.27 1.27)
			)
			(justify left)
		)
		(property "Intersheetrefs" "${INTERSHEET_REFS}"
			(at 246.8579 81.2006 0)
			(effects
				(font
					(size 1.27 1.27)
				)
				(justify left)
			)
		)
	)
	(global_label "POE_OUTPUT"
		(shape output)
		(at 377.19 182.88 0)
		(fields_autoplaced yes)
		(effects
			(font
				(size 1.27 1.27)
			)
			(justify left)
		)
		(property "Intersheetrefs" "${INTERSHEET_REFS}"
			(at 391.5169 182.8006 0)
			(effects
				(font
					(size 1.27 1.27)
				)
				(justify left)
			)
		)
	)
	(global_label "GBE_MDI2_P"
		(shape input)
		(at 166.37 60.96 180)
		(fields_autoplaced yes)
		(effects
			(font
				(size 1.27 1.27)
			)
			(justify right)
		)
		(property "Intersheetrefs" "${INTERSHEET_REFS}"
			(at 152.5269 60.8806 0)
			(effects
				(font
					(size 1.27 1.27)
				)
				(justify right)
			)
		)
	)
	(global_label "GBE_LED_ACT"
		(shape input)
		(at 231.14 76.2 0)
		(fields_autoplaced yes)
		(effects
			(font
				(size 1.27 1.27)
			)
			(justify left)
		)
		(property "Intersheetrefs" "${INTERSHEET_REFS}"
			(at 245.9507 76.1206 0)
			(effects
				(font
					(size 1.27 1.27)
				)
				(justify left)
			)
		)
	)
	(global_label "GBE_MDI0_P"
		(shape input)
		(at 166.37 50.8 180)
		(fields_autoplaced yes)
		(effects
			(font
				(size 1.27 1.27)
			)
			(justify right)
		)
		(property "Intersheetrefs" "${INTERSHEET_REFS}"
			(at 152.5269 50.7206 0)
			(effects
				(font
					(size 1.27 1.27)
				)
				(justify right)
			)
		)
	)
	(global_label "GBE_MDI1_P"
		(shape input)
		(at 166.37 55.88 180)
		(fields_autoplaced yes)
		(effects
			(font
				(size 1.27 1.27)
			)
			(justify right)
		)
		(property "Intersheetrefs" "${INTERSHEET_REFS}"
			(at 152.5269 55.8006 0)
			(effects
				(font
					(size 1.27 1.27)
				)
				(justify right)
			)
		)
	)
	(global_label "GBE_MDI2_N"
		(shape input)
		(at 166.37 63.5 180)
		(fields_autoplaced yes)
		(effects
			(font
				(size 1.27 1.27)
			)
			(justify right)
		)
		(property "Intersheetrefs" "${INTERSHEET_REFS}"
			(at 152.4664 63.4206 0)
			(effects
				(font
					(size 1.27 1.27)
				)
				(justify right)
			)
		)
	)
	(global_label "GBE_MDI1_N"
		(shape input)
		(at 166.37 58.42 180)
		(fields_autoplaced yes)
		(effects
			(font
				(size 1.27 1.27)
			)
			(justify right)
		)
		(property "Intersheetrefs" "${INTERSHEET_REFS}"
			(at 152.4664 58.3406 0)
			(effects
				(font
					(size 1.27 1.27)
				)
				(justify right)
			)
		)
	)
	(netclass_flag ""
		(length 2.54)
		(shape round)
		(at 281.94 236.22 180)
		(fields_autoplaced yes)
		(effects
			(font
				(size 1.27 1.27)
			)
			(justify right bottom)
		)
		(property "Netclass" "PoE"
			(at 282.6385 238.76 0)
			(effects
				(font
					(size 1.27 1.27)
					(italic yes)
				)
				(justify left)
			)
		)
	)
	(netclass_flag ""
		(length 2.54)
		(shape round)
		(at 179.07 73.66 0)
		(fields_autoplaced yes)
		(effects
			(font
				(size 1.27 1.27)
			)
			(justify left bottom)
		)
		(property "Netclass" "PoE"
			(at 179.7685 71.12 0)
			(effects
				(font
					(size 1.27 1.27)
					(italic yes)
				)
				(justify left)
			)
		)
	)
	(netclass_flag ""
		(length 2.54)
		(shape round)
		(at 72.39 213.36 0)
		(fields_autoplaced yes)
		(effects
			(font
				(size 1.27 1.27)
			)
			(justify left bottom)
		)
		(property "Netclass" "PoE"
			(at 73.0885 210.82 0)
			(effects
				(font
					(size 1.27 1.27)
					(italic yes)
				)
				(justify left)
			)
		)
	)
	(netclass_flag ""
		(length 2.54)
		(shape round)
		(at 241.3 201.93 270)
		(fields_autoplaced yes)
		(effects
			(font
				(size 1.27 1.27)
			)
			(justify right bottom)
		)
		(property "Netclass" "PoE"
			(at 243.84 201.2315 90)
			(effects
				(font
					(size 1.27 1.27)
					(italic yes)
				)
				(justify left)
			)
		)
	)
	(netclass_flag ""
		(length 2.54)
		(shape round)
		(at 72.39 182.88 0)
		(fields_autoplaced yes)
		(effects
			(font
				(size 1.27 1.27)
			)
			(justify left bottom)
		)
		(property "Netclass" "PoE"
			(at 73.0885 180.34 0)
			(effects
				(font
					(size 1.27 1.27)
					(italic yes)
				)
				(justify left)
			)
		)
	)
	(symbol
		(lib_id "antmicroCapacitorsmisc:C_22u_100V_2220")
		(at 220.98 204.47 90)
		(unit 1)
		(exclude_from_sim no)
		(in_bom yes)
		(on_board yes)
		(dnp no)
		(property "Reference" "C81"
			(at 222.885 199.39 90)
			(effects
				(font
					(size 1.27 1.27)
				)
				(justify right)
			)
		)
		(property "Value" "C_22u_100V_2220"
			(at 231.14 184.15 0)
			(effects
				(font
					(size 1.27 1.27)
					(thickness 0.15)
				)
				(justify left bottom)
				(hide yes)
			)
		)
		(property "Footprint" "antmicro-footprints:C_2220_5650Metric"
			(at 233.68 184.15 0)
			(effects
				(font
					(size 1.27 1.27)
					(thickness 0.15)
				)
				(justify left bottom)
				(hide yes)
			)
		)
		(property "Datasheet" "https://product.tdk.com/en/search/capacitor/ceramic/mlcc/info?part_no=C5750X7S2A226M280KB"
			(at 236.22 184.15 0)
			(effects
				(font
					(size 1.27 1.27)
					(thickness 0.15)
				)
				(justify left bottom)
				(hide yes)
			)
		)
		(property "Description" ""
			(at 220.98 204.47 0)
			(effects
				(font
					(size 1.27 1.27)
				)
				(hide yes)
			)
		)
		(property "Manufacturer" "TDK"
			(at 241.3 184.15 0)
			(effects
				(font
					(size 1.27 1.27)
					(thickness 0.15)
				)
				(justify left bottom)
				(hide yes)
			)
		)
		(property "MPN" "C5750X7S2A226M280KB"
			(at 238.76 184.15 0)
			(effects
				(font
					(size 1.27 1.27)
					(thickness 0.15)
				)
				(justify left bottom)
				(hide yes)
			)
		)
		(property "Val" "22u"
			(at 222.885 201.93 90)
			(effects
				(font
					(size 1.27 1.27)
					(thickness 0.15)
				)
				(justify right)
			)
		)
		(property "License" "Apache-2.0"
			(at 243.84 184.15 0)
			(effects
				(font
					(size 1.27 1.27)
					(thickness 0.15)
				)
				(justify left bottom)
				(hide yes)
			)
		)
		(property "Author" "Antmicro"
			(at 246.38 184.15 0)
			(effects
				(font
					(size 1.27 1.27)
					(thickness 0.15)
				)
				(justify left bottom)
				(hide yes)
			)
		)
		(property "Voltage" "100V"
			(at 222.885 204.47 90)
			(effects
				(font
					(size 1.27 1.27)
				)
				(justify right)
			)
		)
		(property "Dielectric" "X7S"
			(at 251.46 184.15 0)
			(effects
				(font
					(size 1.27 1.27)
				)
				(justify left bottom)
				(hide yes)
			)
		)
		(property "Public" "False"
			(at 254 184.15 0)
			(effects
				(font
					(size 1.27 1.27)
				)
				(justify left bottom)
				(hide yes)
			)
		)
		(pin "1"
		)
		(pin "2"
		)
		(instances
			(project "jetson-orin-baseboard"
				(path ""
					(reference "C81")
					(unit 1)
				)
			)
		)
	)
	(symbol
		(lib_id "antmicropower:GNDD")
		(at 210.82 218.44 0)
		(unit 1)
		(exclude_from_sim no)
		(in_bom yes)
		(on_board yes)
		(dnp no)
		(property "Reference" "#PWR0139"
			(at 210.82 224.79 0)
			(effects
				(font
					(size 1.27 1.27)
				)
				(justify left bottom)
				(hide yes)
			)
		)
		(property "Value" "GNDD"
			(at 210.82 221.615 0)
			(effects
				(font
					(size 1.27 1.27)
					(thickness 0.15)
				)
			)
		)
		(property "Footprint" ""
			(at 226.06 228.6 0)
			(effects
				(font
					(size 1.27 1.27)
					(thickness 0.15)
				)
				(justify left bottom)
				(hide yes)
			)
		)
		(property "Datasheet" ""
			(at 226.06 231.14 0)
			(effects
				(font
					(size 1.27 1.27)
					(thickness 0.15)
				)
				(justify left bottom)
				(hide yes)
			)
		)
		(property "Description" ""
			(at 210.82 218.44 0)
			(effects
				(font
					(size 1.27 1.27)
				)
				(hide yes)
			)
		)
		(property "Author" "Antmicro"
			(at 226.06 226.06 0)
			(effects
				(font
					(size 1.27 1.27)
					(thickness 0.15)
				)
				(justify left bottom)
				(hide yes)
			)
		)
		(property "License" "Apache-2.0"
			(at 226.06 228.6 0)
			(effects
				(font
					(size 1.27 1.27)
					(thickness 0.15)
				)
				(justify left bottom)
				(hide yes)
			)
		)
		(pin "1"
		)
		(instances
			(project "jetson-orin-baseboard"
				(path ""
					(reference "#PWR0139")
					(unit 1)
				)
			)
		)
	)
	(symbol
		(lib_id "antmicroFerriteBeadsandChips:FB_220Z_2A_Murata-BLM21PG_0805")
		(at 83.82 182.88 0)
		(unit 1)
		(exclude_from_sim no)
		(in_bom yes)
		(on_board yes)
		(dnp no)
		(fields_autoplaced yes)
		(property "Reference" "FB2"
			(at 86.3219 176.53 0)
			(effects
				(font
					(size 1.27 1.27)
				)
			)
		)
		(property "Value" "FB_220Z_2A_Murata-BLM21PG_0805"
			(at 97.79 185.42 0)
			(effects
				(font
					(size 1.27 1.27)
					(thickness 0.15)
				)
				(justify left bottom)
				(hide yes)
			)
		)
		(property "Footprint" "antmicro-footprints:FB_0805_2012Metric"
			(at 97.79 190.5 0)
			(effects
				(font
					(size 1.27 1.27)
					(thickness 0.15)
				)
				(justify left bottom)
				(hide yes)
			)
		)
		(property "Datasheet" "https://www.murata.com/products/productdata/8796738977822/ENFA0005.pdf?1653276712000"
			(at 97.79 193.04 0)
			(effects
				(font
					(size 1.27 1.27)
					(thickness 0.15)
				)
				(justify left bottom)
				(hide yes)
			)
		)
		(property "Description" ""
			(at 83.82 182.88 0)
			(effects
				(font
					(size 1.27 1.27)
				)
				(hide yes)
			)
		)
		(property "MPN" "BLM21PG221SN1D"
			(at 97.79 195.58 0)
			(effects
				(font
					(size 1.27 1.27)
					(thickness 0.15)
				)
				(justify left bottom)
				(hide yes)
			)
		)
		(property "Manufacturer" "Murata"
			(at 97.79 198.12 0)
			(effects
				(font
					(size 1.27 1.27)
					(thickness 0.15)
				)
				(justify left bottom)
				(hide yes)
			)
		)
		(property "Author" "Antmicro"
			(at 97.79 200.66 0)
			(effects
				(font
					(size 1.27 1.27)
					(thickness 0.15)
				)
				(justify left bottom)
				(hide yes)
			)
		)
		(property "License" "Apache-2.0"
			(at 97.79 203.2 0)
			(effects
				(font
					(size 1.27 1.27)
					(thickness 0.15)
				)
				(justify left bottom)
				(hide yes)
			)
		)
		(property "Val" "220Z/2A"
			(at 86.3219 179.07 0)
			(effects
				(font
					(size 1.27 1.27)
				)
			)
		)
		(property "Current" ""
			(at 104.14 205.74 0)
			(effects
				(font
					(size 1.27 1.27)
					(thickness 0.15)
				)
				(justify left bottom)
				(hide yes)
			)
		)
		(pin "1"
		)
		(pin "2"
		)
		(instances
			(project "jetson-orin-baseboard"
				(path ""
					(reference "FB2")
					(unit 1)
				)
			)
		)
	)
	(symbol
		(lib_id "antmicroResistors0402:R_1k_0402")
		(at 273.05 236.22 0)
		(unit 1)
		(exclude_from_sim no)
		(in_bom yes)
		(on_board yes)
		(dnp no)
		(property "Reference" "R155"
			(at 278.13 235.585 0)
			(effects
				(font
					(size 1.27 1.27)
				)
				(justify left bottom)
			)
		)
		(property "Value" "R_1k_0402"
			(at 293.37 248.92 0)
			(effects
				(font
					(size 1.27 1.27)
					(thickness 0.15)
				)
				(justify left bottom)
				(hide yes)
			)
		)
		(property "Footprint" "antmicro-footprints:R_0402_1005Metric"
			(at 293.37 251.46 0)
			(effects
				(font
					(size 1.27 1.27)
					(thickness 0.15)
				)
				(justify left bottom)
				(hide yes)
			)
		)
		(property "Datasheet" "https://www.bourns.com/docs/product-datasheets/cr.pdf"
			(at 293.37 254 0)
			(effects
				(font
					(size 1.27 1.27)
					(thickness 0.15)
				)
				(justify left bottom)
				(hide yes)
			)
		)
		(property "Description" ""
			(at 273.05 236.22 0)
			(effects
				(font
					(size 1.27 1.27)
				)
				(hide yes)
			)
		)
		(property "Manufacturer" "Bourns"
			(at 293.37 259.08 0)
			(effects
				(font
					(size 1.27 1.27)
					(thickness 0.15)
				)
				(justify left bottom)
				(hide yes)
			)
		)
		(property "MPN" "CR0402-FX-1001GLF"
			(at 293.37 256.54 0)
			(effects
				(font
					(size 1.27 1.27)
					(thickness 0.15)
				)
				(justify left bottom)
				(hide yes)
			)
		)
		(property "Val" "1k"
			(at 270.51 235.585 0)
			(effects
				(font
					(size 1.27 1.27)
					(thickness 0.15)
				)
				(justify left bottom)
			)
		)
		(property "License" "Apache-2.0"
			(at 293.37 261.62 0)
			(effects
				(font
					(size 1.27 1.27)
					(thickness 0.15)
				)
				(justify left bottom)
				(hide yes)
			)
		)
		(property "Author" "Antmicro"
			(at 293.37 264.16 0)
			(effects
				(font
					(size 1.27 1.27)
					(thickness 0.15)
				)
				(justify left bottom)
				(hide yes)
			)
		)
		(property "Tolerance" "1%"
			(at 293.37 246.38 0)
			(effects
				(font
					(size 1.27 1.27)
				)
				(justify left bottom)
				(hide yes)
			)
		)
		(pin "1"
		)
		(pin "2"
		)
		(instances
			(project "jetson-orin-baseboard"
				(path ""
					(reference "R155")
					(unit 1)
				)
			)
		)
	)
	(symbol
		(lib_id "antmicropower:GND")
		(at 220.98 93.98 0)
		(unit 1)
		(exclude_from_sim no)
		(in_bom yes)
		(on_board yes)
		(dnp no)
		(property "Reference" "#PWR0136"
			(at 220.98 100.33 0)
			(effects
				(font
					(size 1.27 1.27)
				)
				(justify left bottom)
				(hide yes)
			)
		)
		(property "Value" "GND"
			(at 220.98 97.79 0)
			(effects
				(font
					(size 1.27 1.27)
					(thickness 0.15)
				)
			)
		)
		(property "Footprint" ""
			(at 229.87 101.6 0)
			(effects
				(font
					(size 1.27 1.27)
					(thickness 0.15)
				)
				(justify left bottom)
				(hide yes)
			)
		)
		(property "Datasheet" ""
			(at 229.87 106.68 0)
			(effects
				(font
					(size 1.27 1.27)
					(thickness 0.15)
				)
				(justify left bottom)
				(hide yes)
			)
		)
		(property "Description" ""
			(at 220.98 93.98 0)
			(effects
				(font
					(size 1.27 1.27)
				)
				(hide yes)
			)
		)
		(property "Author" "Antmicro"
			(at 229.87 101.6 0)
			(effects
				(font
					(size 1.27 1.27)
					(thickness 0.15)
				)
				(justify left bottom)
				(hide yes)
			)
		)
		(property "License" "Apache-2.0"
			(at 229.87 104.14 0)
			(effects
				(font
					(size 1.27 1.27)
					(thickness 0.15)
				)
				(justify left bottom)
				(hide yes)
			)
		)
		(pin "1"
		)
		(instances
			(project "jetson-orin-baseboard"
				(path ""
					(reference "#PWR0136")
					(unit 1)
				)
			)
		)
	)
	(symbol
		(lib_id "antmicropower:GNDD")
		(at 274.32 217.17 0)
		(unit 1)
		(exclude_from_sim no)
		(in_bom yes)
		(on_board yes)
		(dnp no)
		(property "Reference" "#PWR0302"
			(at 274.32 223.52 0)
			(effects
				(font
					(size 1.27 1.27)
				)
				(justify left bottom)
				(hide yes)
			)
		)
		(property "Value" "GNDD"
			(at 274.32 220.345 0)
			(effects
				(font
					(size 1.27 1.27)
					(thickness 0.15)
				)
			)
		)
		(property "Footprint" ""
			(at 289.56 227.33 0)
			(effects
				(font
					(size 1.27 1.27)
					(thickness 0.15)
				)
				(justify left bottom)
				(hide yes)
			)
		)
		(property "Datasheet" ""
			(at 289.56 229.87 0)
			(effects
				(font
					(size 1.27 1.27)
					(thickness 0.15)
				)
				(justify left bottom)
				(hide yes)
			)
		)
		(property "Description" ""
			(at 274.32 217.17 0)
			(effects
				(font
					(size 1.27 1.27)
				)
				(hide yes)
			)
		)
		(property "Author" "Antmicro"
			(at 289.56 224.79 0)
			(effects
				(font
					(size 1.27 1.27)
					(thickness 0.15)
				)
				(justify left bottom)
				(hide yes)
			)
		)
		(property "License" "Apache-2.0"
			(at 289.56 227.33 0)
			(effects
				(font
					(size 1.27 1.27)
					(thickness 0.15)
				)
				(justify left bottom)
				(hide yes)
			)
		)
		(pin "1"
		)
		(instances
			(project "jetson-orin-baseboard"
				(path ""
					(reference "#PWR0302")
					(unit 1)
				)
			)
		)
	)
	(symbol
		(lib_id "antmicropower:GND")
		(at 369.57 199.39 0)
		(unit 1)
		(exclude_from_sim no)
		(in_bom yes)
		(on_board yes)
		(dnp no)
		(property "Reference" "#PWR0148"
			(at 369.57 205.74 0)
			(effects
				(font
					(size 1.27 1.27)
				)
				(justify left bottom)
				(hide yes)
			)
		)
		(property "Value" "GND"
			(at 369.57 203.2 0)
			(effects
				(font
					(size 1.27 1.27)
					(thickness 0.15)
				)
			)
		)
		(property "Footprint" ""
			(at 378.46 207.01 0)
			(effects
				(font
					(size 1.27 1.27)
					(thickness 0.15)
				)
				(justify left bottom)
				(hide yes)
			)
		)
		(property "Datasheet" ""
			(at 378.46 212.09 0)
			(effects
				(font
					(size 1.27 1.27)
					(thickness 0.15)
				)
				(justify left bottom)
				(hide yes)
			)
		)
		(property "Description" ""
			(at 369.57 199.39 0)
			(effects
				(font
					(size 1.27 1.27)
				)
				(hide yes)
			)
		)
		(property "Author" "Antmicro"
			(at 378.46 207.01 0)
			(effects
				(font
					(size 1.27 1.27)
					(thickness 0.15)
				)
				(justify left bottom)
				(hide yes)
			)
		)
		(property "License" "Apache-2.0"
			(at 378.46 209.55 0)
			(effects
				(font
					(size 1.27 1.27)
					(thickness 0.15)
				)
				(justify left bottom)
				(hide yes)
			)
		)
		(pin "1"
		)
		(instances
			(project "jetson-orin-baseboard"
				(path ""
					(reference "#PWR0148")
					(unit 1)
				)
			)
		)
	)
	(symbol
		(lib_id "antmicroResistors0402:R_1k_0402")
		(at 303.53 236.22 0)
		(unit 1)
		(exclude_from_sim no)
		(in_bom yes)
		(on_board yes)
		(dnp no)
		(property "Reference" "R156"
			(at 308.61 235.585 0)
			(effects
				(font
					(size 1.27 1.27)
				)
				(justify left bottom)
			)
		)
		(property "Value" "R_1k_0402"
			(at 323.85 248.92 0)
			(effects
				(font
					(size 1.27 1.27)
					(thickness 0.15)
				)
				(justify left bottom)
				(hide yes)
			)
		)
		(property "Footprint" "antmicro-footprints:R_0402_1005Metric"
			(at 323.85 251.46 0)
			(effects
				(font
					(size 1.27 1.27)
					(thickness 0.15)
				)
				(justify left bottom)
				(hide yes)
			)
		)
		(property "Datasheet" "https://www.bourns.com/docs/product-datasheets/cr.pdf"
			(at 323.85 254 0)
			(effects
				(font
					(size 1.27 1.27)
					(thickness 0.15)
				)
				(justify left bottom)
				(hide yes)
			)
		)
		(property "Description" ""
			(at 303.53 236.22 0)
			(effects
				(font
					(size 1.27 1.27)
				)
				(hide yes)
			)
		)
		(property "Manufacturer" "Bourns"
			(at 323.85 259.08 0)
			(effects
				(font
					(size 1.27 1.27)
					(thickness 0.15)
				)
				(justify left bottom)
				(hide yes)
			)
		)
		(property "MPN" "CR0402-FX-1001GLF"
			(at 323.85 256.54 0)
			(effects
				(font
					(size 1.27 1.27)
					(thickness 0.15)
				)
				(justify left bottom)
				(hide yes)
			)
		)
		(property "Val" "1k"
			(at 300.99 235.585 0)
			(effects
				(font
					(size 1.27 1.27)
					(thickness 0.15)
				)
				(justify left bottom)
			)
		)
		(property "License" "Apache-2.0"
			(at 323.85 261.62 0)
			(effects
				(font
					(size 1.27 1.27)
					(thickness 0.15)
				)
				(justify left bottom)
				(hide yes)
			)
		)
		(property "Author" "Antmicro"
			(at 323.85 264.16 0)
			(effects
				(font
					(size 1.27 1.27)
					(thickness 0.15)
				)
				(justify left bottom)
				(hide yes)
			)
		)
		(property "Tolerance" "1%"
			(at 323.85 246.38 0)
			(effects
				(font
					(size 1.27 1.27)
				)
				(justify left bottom)
				(hide yes)
			)
		)
		(pin "1"
		)
		(pin "2"
		)
		(instances
			(project "jetson-orin-baseboard"
				(path ""
					(reference "R156")
					(unit 1)
				)
			)
		)
	)
	(symbol
		(lib_id "antmicropower:GND")
		(at 339.09 199.39 0)
		(unit 1)
		(exclude_from_sim no)
		(in_bom yes)
		(on_board yes)
		(dnp no)
		(property "Reference" "#PWR0308"
			(at 339.09 205.74 0)
			(effects
				(font
					(size 1.27 1.27)
				)
				(justify left bottom)
				(hide yes)
			)
		)
		(property "Value" "GND"
			(at 339.09 203.2 0)
			(effects
				(font
					(size 1.27 1.27)
					(thickness 0.15)
				)
			)
		)
		(property "Footprint" ""
			(at 347.98 207.01 0)
			(effects
				(font
					(size 1.27 1.27)
					(thickness 0.15)
				)
				(justify left bottom)
				(hide yes)
			)
		)
		(property "Datasheet" ""
			(at 347.98 212.09 0)
			(effects
				(font
					(size 1.27 1.27)
					(thickness 0.15)
				)
				(justify left bottom)
				(hide yes)
			)
		)
		(property "Description" ""
			(at 339.09 199.39 0)
			(effects
				(font
					(size 1.27 1.27)
				)
				(hide yes)
			)
		)
		(property "Author" "Antmicro"
			(at 347.98 207.01 0)
			(effects
				(font
					(size 1.27 1.27)
					(thickness 0.15)
				)
				(justify left bottom)
				(hide yes)
			)
		)
		(property "License" "Apache-2.0"
			(at 347.98 209.55 0)
			(effects
				(font
					(size 1.27 1.27)
					(thickness 0.15)
				)
				(justify left bottom)
				(hide yes)
			)
		)
		(pin "1"
		)
		(instances
			(project "jetson-orin-baseboard"
				(path ""
					(reference "#PWR0308")
					(unit 1)
				)
			)
		)
	)
	(symbol
		(lib_id "antmicroOptoisolatorsLogicOutput:ACPL-217-500E")
		(at 298.45 232.41 0)
		(mirror y)
		(unit 1)
		(exclude_from_sim no)
		(in_bom yes)
		(on_board yes)
		(dnp no)
		(property "Reference" "U39"
			(at 292.1 226.695 0)
			(effects
				(font
					(size 1.27 1.27)
					(thickness 0.15)
				)
			)
		)
		(property "Value" "ACPL-217-500E"
			(at 270.51 240.03 0)
			(effects
				(font
					(size 1.27 1.27)
					(thickness 0.15)
				)
				(justify left bottom)
				(hide yes)
			)
		)
		(property "Footprint" "antmicro-footprints:SOIC-4_4.55x2.6mm_P1.27mm"
			(at 270.51 242.57 0)
			(effects
				(font
					(size 1.27 1.27)
					(thickness 0.15)
				)
				(justify left bottom)
				(hide yes)
			)
		)
		(property "Datasheet" "https://docs.broadcom.com/doc/AV02-0470EN"
			(at 270.51 245.11 0)
			(effects
				(font
					(size 1.27 1.27)
					(thickness 0.15)
				)
				(justify left bottom)
				(hide yes)
			)
		)
		(property "Description" "Broadcom ACPL-217-500E DC Input Transistor Output Optocoupler, Surface Mount, 4-Pin SO"
			(at 270.51 247.65 0)
			(effects
				(font
					(size 1.27 1.27)
					(thickness 0.15)
				)
				(justify left bottom)
				(hide yes)
			)
		)
		(property "Manufacturer" "Broadcom"
			(at 270.51 250.19 0)
			(effects
				(font
					(size 1.27 1.27)
					(thickness 0.15)
				)
				(justify left bottom)
				(hide yes)
			)
		)
		(property "MPN" "ACPL-217-500E"
			(at 292.1 229.235 0)
			(effects
				(font
					(size 1.27 1.27)
					(thickness 0.15)
				)
			)
		)
		(property "Author" "Antmicro"
			(at 270.51 255.27 0)
			(effects
				(font
					(size 1.27 1.27)
					(thickness 0.15)
				)
				(justify left bottom)
				(hide yes)
			)
		)
		(property "License" "Apache-2.0"
			(at 270.51 257.81 0)
			(effects
				(font
					(size 1.27 1.27)
					(thickness 0.15)
				)
				(justify left bottom)
				(hide yes)
			)
		)
		(pin "1"
		)
		(pin "2"
		)
		(pin "3"
		)
		(pin "4"
		)
		(instances
			(project "jetson-orin-baseboard"
				(path ""
					(reference "U39")
					(unit 1)
				)
			)
		)
	)
	(symbol
		(lib_id "antmicroResistors0402:R_0R_0402")
		(at 118.11 220.98 180)
		(unit 1)
		(exclude_from_sim no)
		(in_bom yes)
		(on_board yes)
		(dnp no)
		(property "Reference" "R129"
			(at 118.11 220.345 0)
			(effects
				(font
					(size 1.27 1.27)
				)
				(justify right top)
			)
		)
		(property "Value" "R_0R_0402"
			(at 97.79 208.28 0)
			(effects
				(font
					(size 1.27 1.27)
					(thickness 0.15)
				)
				(justify left bottom)
				(hide yes)
			)
		)
		(property "Footprint" "antmicro-footprints:R_0402_1005Metric"
			(at 97.79 205.74 0)
			(effects
				(font
					(size 1.27 1.27)
					(thickness 0.15)
				)
				(justify left bottom)
				(hide yes)
			)
		)
		(property "Datasheet" "https://industrial.panasonic.com/cdbs/www-data/pdf/RDA0000/AOA0000C301.pdf"
			(at 97.79 203.2 0)
			(effects
				(font
					(size 1.27 1.27)
					(thickness 0.15)
				)
				(justify left bottom)
				(hide yes)
			)
		)
		(property "Description" ""
			(at 118.11 220.98 0)
			(effects
				(font
					(size 1.27 1.27)
				)
				(hide yes)
			)
		)
		(property "Manufacturer" "Panasonic"
			(at 97.79 198.12 0)
			(effects
				(font
					(size 1.27 1.27)
					(thickness 0.15)
				)
				(justify left bottom)
				(hide yes)
			)
		)
		(property "MPN" "ERJ2GE0R00X"
			(at 97.79 200.66 0)
			(effects
				(font
					(size 1.27 1.27)
					(thickness 0.15)
				)
				(justify left bottom)
				(hide yes)
			)
		)
		(property "Val" "0R"
			(at 110.49 220.345 0)
			(effects
				(font
					(size 1.27 1.27)
					(thickness 0.15)
				)
				(justify right top)
			)
		)
		(property "License" "Apache-2.0"
			(at 97.79 195.58 0)
			(effects
				(font
					(size 1.27 1.27)
					(thickness 0.15)
				)
				(justify left bottom)
				(hide yes)
			)
		)
		(property "Author" "Antmicro"
			(at 97.79 193.04 0)
			(effects
				(font
					(size 1.27 1.27)
					(thickness 0.15)
				)
				(justify left bottom)
				(hide yes)
			)
		)
		(property "Tolerance" "~"
			(at 97.79 210.82 0)
			(effects
				(font
					(size 1.27 1.27)
				)
				(justify left bottom)
				(hide yes)
			)
		)
		(property "Current" "1A"
			(at 97.79 190.5 0)
			(effects
				(font
					(size 1.27 1.27)
					(thickness 0.15)
				)
				(justify left bottom)
				(hide yes)
			)
		)
		(pin "1"
		)
		(pin "2"
		)
		(instances
			(project "jetson-orin-baseboard"
				(path ""
					(reference "R129")
					(unit 1)
				)
			)
		)
	)
	(symbol
		(lib_id "antmicroFerriteBeadsandChips:FB_220Z_2A_Murata-BLM21PG_0805")
		(at 83.82 213.36 0)
		(unit 1)
		(exclude_from_sim no)
		(in_bom yes)
		(on_board yes)
		(dnp no)
		(fields_autoplaced yes)
		(property "Reference" "FB3"
			(at 86.3219 207.01 0)
			(effects
				(font
					(size 1.27 1.27)
				)
			)
		)
		(property "Value" "FB_220Z_2A_Murata-BLM21PG_0805"
			(at 97.79 215.9 0)
			(effects
				(font
					(size 1.27 1.27)
					(thickness 0.15)
				)
				(justify left bottom)
				(hide yes)
			)
		)
		(property "Footprint" "antmicro-footprints:FB_0805_2012Metric"
			(at 97.79 220.98 0)
			(effects
				(font
					(size 1.27 1.27)
					(thickness 0.15)
				)
				(justify left bottom)
				(hide yes)
			)
		)
		(property "Datasheet" "https://www.murata.com/products/productdata/8796738977822/ENFA0005.pdf?1653276712000"
			(at 97.79 223.52 0)
			(effects
				(font
					(size 1.27 1.27)
					(thickness 0.15)
				)
				(justify left bottom)
				(hide yes)
			)
		)
		(property "Description" ""
			(at 83.82 213.36 0)
			(effects
				(font
					(size 1.27 1.27)
				)
				(hide yes)
			)
		)
		(property "MPN" "BLM21PG221SN1D"
			(at 97.79 226.06 0)
			(effects
				(font
					(size 1.27 1.27)
					(thickness 0.15)
				)
				(justify left bottom)
				(hide yes)
			)
		)
		(property "Manufacturer" "Murata"
			(at 97.79 228.6 0)
			(effects
				(font
					(size 1.27 1.27)
					(thickness 0.15)
				)
				(justify left bottom)
				(hide yes)
			)
		)
		(property "Author" "Antmicro"
			(at 97.79 231.14 0)
			(effects
				(font
					(size 1.27 1.27)
					(thickness 0.15)
				)
				(justify left bottom)
				(hide yes)
			)
		)
		(property "License" "Apache-2.0"
			(at 97.79 233.68 0)
			(effects
				(font
					(size 1.27 1.27)
					(thickness 0.15)
				)
				(justify left bottom)
				(hide yes)
			)
		)
		(property "Val" "220Z/2A"
			(at 86.3219 209.55 0)
			(effects
				(font
					(size 1.27 1.27)
				)
			)
		)
		(property "Current" ""
			(at 104.14 236.22 0)
			(effects
				(font
					(size 1.27 1.27)
					(thickness 0.15)
				)
				(justify left bottom)
				(hide yes)
			)
		)
		(pin "1"
		)
		(pin "2"
		)
		(instances
			(project "jetson-orin-baseboard"
				(path ""
					(reference "FB3")
					(unit 1)
				)
			)
		)
	)
	(symbol
		(lib_id "antmicroResistors0402:R_10k_0402")
		(at 179.07 189.23 90)
		(unit 1)
		(exclude_from_sim no)
		(in_bom no)
		(on_board yes)
		(dnp yes)
		(property "Reference" "R150"
			(at 180.34 185.42 90)
			(effects
				(font
					(size 1.27 1.27)
				)
				(justify right)
			)
		)
		(property "Value" "R_10k_0402"
			(at 191.77 168.91 0)
			(effects
				(font
					(size 1.27 1.27)
					(thickness 0.15)
				)
				(justify left bottom)
				(hide yes)
			)
		)
		(property "Footprint" "antmicro-footprints:R_0402_1005Metric"
			(at 194.31 168.91 0)
			(effects
				(font
					(size 1.27 1.27)
					(thickness 0.15)
				)
				(justify left bottom)
				(hide yes)
			)
		)
		(property "Datasheet" "https://www.bourns.com/docs/product-datasheets/cr.pdf"
			(at 196.85 168.91 0)
			(effects
				(font
					(size 1.27 1.27)
					(thickness 0.15)
				)
				(justify left bottom)
				(hide yes)
			)
		)
		(property "Description" ""
			(at 179.07 189.23 0)
			(effects
				(font
					(size 1.27 1.27)
				)
				(hide yes)
			)
		)
		(property "Manufacturer" "Bourns"
			(at 201.93 168.91 0)
			(effects
				(font
					(size 1.27 1.27)
					(thickness 0.15)
				)
				(justify left bottom)
				(hide yes)
			)
		)
		(property "MPN" "CR0402-FX-1002GLF"
			(at 199.39 168.91 0)
			(effects
				(font
					(size 1.27 1.27)
					(thickness 0.15)
				)
				(justify left bottom)
				(hide yes)
			)
		)
		(property "Val" "10k"
			(at 180.34 187.96 90)
			(effects
				(font
					(size 1.27 1.27)
					(thickness 0.15)
				)
				(justify right)
			)
		)
		(property "License" "Apache-2.0"
			(at 204.47 168.91 0)
			(effects
				(font
					(size 1.27 1.27)
					(thickness 0.15)
				)
				(justify left bottom)
				(hide yes)
			)
		)
		(property "Author" "Antmicro"
			(at 207.01 168.91 0)
			(effects
				(font
					(size 1.27 1.27)
					(thickness 0.15)
				)
				(justify left bottom)
				(hide yes)
			)
		)
		(property "Tolerance" "1%"
			(at 189.23 168.91 0)
			(effects
				(font
					(size 1.27 1.27)
				)
				(justify left bottom)
				(hide yes)
			)
		)
		(pin "1"
		)
		(pin "2"
		)
		(instances
			(project "jetson-orin-baseboard"
				(path ""
					(reference "R150")
					(unit 1)
				)
			)
		)
	)
	(symbol
		(lib_id "antmicropower:GND")
		(at 179.07 93.98 0)
		(unit 1)
		(exclude_from_sim no)
		(in_bom yes)
		(on_board yes)
		(dnp no)
		(property "Reference" "#PWR0134"
			(at 179.07 100.33 0)
			(effects
				(font
					(size 1.27 1.27)
				)
				(justify left bottom)
				(hide yes)
			)
		)
		(property "Value" "GND"
			(at 179.07 97.79 0)
			(effects
				(font
					(size 1.27 1.27)
					(thickness 0.15)
				)
			)
		)
		(property "Footprint" ""
			(at 187.96 101.6 0)
			(effects
				(font
					(size 1.27 1.27)
					(thickness 0.15)
				)
				(justify left bottom)
				(hide yes)
			)
		)
		(property "Datasheet" ""
			(at 187.96 106.68 0)
			(effects
				(font
					(size 1.27 1.27)
					(thickness 0.15)
				)
				(justify left bottom)
				(hide yes)
			)
		)
		(property "Description" ""
			(at 179.07 93.98 0)
			(effects
				(font
					(size 1.27 1.27)
				)
				(hide yes)
			)
		)
		(property "Author" "Antmicro"
			(at 187.96 101.6 0)
			(effects
				(font
					(size 1.27 1.27)
					(thickness 0.15)
				)
				(justify left bottom)
				(hide yes)
			)
		)
		(property "License" "Apache-2.0"
			(at 187.96 104.14 0)
			(effects
				(font
					(size 1.27 1.27)
					(thickness 0.15)
				)
				(justify left bottom)
				(hide yes)
			)
		)
		(pin "1"
		)
		(instances
			(project "jetson-orin-baseboard"
				(path ""
					(reference "#PWR0134")
					(unit 1)
				)
			)
		)
	)
	(symbol
		(lib_id "antmicroResistors0603:R_63R4_0603")
		(at 124.46 209.55 270)
		(mirror x)
		(unit 1)
		(exclude_from_sim no)
		(in_bom yes)
		(on_board yes)
		(dnp no)
		(property "Reference" "R196"
			(at 123.19 205.74 90)
			(effects
				(font
					(size 1.27 1.27)
				)
				(justify right)
			)
		)
		(property "Value" "R_63R4_0603"
			(at 111.76 189.23 0)
			(effects
				(font
					(size 1.27 1.27)
					(thickness 0.15)
				)
				(justify left bottom)
				(hide yes)
			)
		)
		(property "Footprint" "antmicro-footprints:R_0603_1608Metric"
			(at 109.22 189.23 0)
			(effects
				(font
					(size 1.27 1.27)
					(thickness 0.15)
				)
				(justify left bottom)
				(hide yes)
			)
		)
		(property "Datasheet" "https://www.bourns.com/docs/product-datasheets/cr.pdf"
			(at 106.68 189.23 0)
			(effects
				(font
					(size 1.27 1.27)
					(thickness 0.15)
				)
				(justify left bottom)
				(hide yes)
			)
		)
		(property "Description" ""
			(at 124.46 209.55 0)
			(effects
				(font
					(size 1.27 1.27)
				)
				(hide yes)
			)
		)
		(property "Manufacturer" "Bourns"
			(at 101.6 189.23 0)
			(effects
				(font
					(size 1.27 1.27)
					(thickness 0.15)
				)
				(justify left bottom)
				(hide yes)
			)
		)
		(property "MPN" "CR0603-FX-63R4ELF"
			(at 104.14 189.23 0)
			(effects
				(font
					(size 1.27 1.27)
					(thickness 0.15)
				)
				(justify left bottom)
				(hide yes)
			)
		)
		(property "Val" "63R4"
			(at 123.19 208.28 90)
			(effects
				(font
					(size 1.27 1.27)
					(thickness 0.15)
				)
				(justify right)
			)
		)
		(property "License" "Apache-2.0"
			(at 99.06 189.23 0)
			(effects
				(font
					(size 1.27 1.27)
					(thickness 0.15)
				)
				(justify left bottom)
				(hide yes)
			)
		)
		(property "Author" "Antmicro"
			(at 96.52 189.23 0)
			(effects
				(font
					(size 1.27 1.27)
					(thickness 0.15)
				)
				(justify left bottom)
				(hide yes)
			)
		)
		(property "Tolerance" "1%"
			(at 114.3 189.23 0)
			(effects
				(font
					(size 1.27 1.27)
				)
				(justify left bottom)
				(hide yes)
			)
		)
		(pin "1"
		)
		(pin "2"
		)
		(instances
			(project "jetson-orin-baseboard"
				(path ""
					(reference "R196")
					(unit 1)
				)
			)
		)
	)
	(symbol
		(lib_id "antmicroCapacitorsmisc:C_22u_100V_2220")
		(at 200.66 204.47 90)
		(unit 1)
		(exclude_from_sim no)
		(in_bom yes)
		(on_board yes)
		(dnp no)
		(property "Reference" "C79"
			(at 202.565 199.39 90)
			(effects
				(font
					(size 1.27 1.27)
				)
				(justify right)
			)
		)
		(property "Value" "C_22u_100V_2220"
			(at 210.82 184.15 0)
			(effects
				(font
					(size 1.27 1.27)
					(thickness 0.15)
				)
				(justify left bottom)
				(hide yes)
			)
		)
		(property "Footprint" "antmicro-footprints:C_2220_5650Metric"
			(at 213.36 184.15 0)
			(effects
				(font
					(size 1.27 1.27)
					(thickness 0.15)
				)
				(justify left bottom)
				(hide yes)
			)
		)
		(property "Datasheet" "https://product.tdk.com/en/search/capacitor/ceramic/mlcc/info?part_no=C5750X7S2A226M280KB"
			(at 215.9 184.15 0)
			(effects
				(font
					(size 1.27 1.27)
					(thickness 0.15)
				)
				(justify left bottom)
				(hide yes)
			)
		)
		(property "Description" ""
			(at 200.66 204.47 0)
			(effects
				(font
					(size 1.27 1.27)
				)
				(hide yes)
			)
		)
		(property "Manufacturer" "TDK"
			(at 220.98 184.15 0)
			(effects
				(font
					(size 1.27 1.27)
					(thickness 0.15)
				)
				(justify left bottom)
				(hide yes)
			)
		)
		(property "MPN" "C5750X7S2A226M280KB"
			(at 218.44 184.15 0)
			(effects
				(font
					(size 1.27 1.27)
					(thickness 0.15)
				)
				(justify left bottom)
				(hide yes)
			)
		)
		(property "Val" "22u"
			(at 202.565 201.93 90)
			(effects
				(font
					(size 1.27 1.27)
					(thickness 0.15)
				)
				(justify right)
			)
		)
		(property "License" "Apache-2.0"
			(at 223.52 184.15 0)
			(effects
				(font
					(size 1.27 1.27)
					(thickness 0.15)
				)
				(justify left bottom)
				(hide yes)
			)
		)
		(property "Author" "Antmicro"
			(at 226.06 184.15 0)
			(effects
				(font
					(size 1.27 1.27)
					(thickness 0.15)
				)
				(justify left bottom)
				(hide yes)
			)
		)
		(property "Voltage" "100V"
			(at 202.565 204.47 90)
			(effects
				(font
					(size 1.27 1.27)
				)
				(justify right)
			)
		)
		(property "Dielectric" "X7S"
			(at 231.14 184.15 0)
			(effects
				(font
					(size 1.27 1.27)
				)
				(justify left bottom)
				(hide yes)
			)
		)
		(property "Public" "False"
			(at 233.68 184.15 0)
			(effects
				(font
					(size 1.27 1.27)
				)
				(justify left bottom)
				(hide yes)
			)
		)
		(pin "1"
		)
		(pin "2"
		)
		(instances
			(project "jetson-orin-baseboard"
				(path ""
					(reference "C79")
					(unit 1)
				)
			)
		)
	)
	(symbol
		(lib_id "antmicroDCDCConverters:ULS-12_5-D48N-C")
		(at 307.34 182.88 0)
		(unit 1)
		(exclude_from_sim no)
		(in_bom yes)
		(on_board yes)
		(dnp no)
		(property "Reference" "U23"
			(at 317.5 176.53 0)
			(effects
				(font
					(size 1.27 1.27)
				)
			)
		)
		(property "Value" "ULS-12_5-D48N-C"
			(at 340.36 190.5 0)
			(effects
				(font
					(size 1.27 1.27)
					(thickness 0.15)
				)
				(justify left bottom)
				(hide yes)
			)
		)
		(property "Footprint" "antmicro-footprints:Conv_Murata_ULS-60W"
			(at 340.36 193.04 0)
			(effects
				(font
					(size 1.27 1.27)
					(thickness 0.15)
				)
				(justify left bottom)
				(hide yes)
			)
		)
		(property "Datasheet" "https://www.murata.com/products/productdata/8807040286750/uls.pdf?1649388617000"
			(at 340.36 195.58 0)
			(effects
				(font
					(size 1.27 1.27)
					(thickness 0.15)
				)
				(justify left bottom)
				(hide yes)
			)
		)
		(property "Description" "Isolated Through Hole DC/DC Converter, ITE, 2:1, 60 W, 1 Output, 12 V, 5 A"
			(at 307.34 182.88 0)
			(effects
				(font
					(size 1.27 1.27)
				)
				(hide yes)
			)
		)
		(property "Manufacturer" "Murata"
			(at 340.36 198.12 0)
			(effects
				(font
					(size 1.27 1.27)
					(thickness 0.15)
				)
				(justify left bottom)
				(hide yes)
			)
		)
		(property "MPN" "ULS-12/5-D48N-C"
			(at 317.5 179.07 0)
			(effects
				(font
					(size 1.27 1.27)
					(thickness 0.15)
				)
			)
		)
		(property "Author" "Antmicro"
			(at 340.36 200.66 0)
			(effects
				(font
					(size 1.27 1.27)
					(thickness 0.15)
				)
				(justify left bottom)
				(hide yes)
			)
		)
		(property "License" "Apache-2.0"
			(at 340.36 203.2 0)
			(effects
				(font
					(size 1.27 1.27)
					(thickness 0.15)
				)
				(justify left bottom)
				(hide yes)
			)
		)
		(property "Alternatives 50W" " VCB4812SBO-50WR3, V36SE12004NRFA, PKU5513ESI, KHHD004A2B41Z"
			(at 297.18 205.74 0)
			(effects
				(font
					(size 1.27 1.27)
				)
				(justify left)
				(hide yes)
			)
		)
		(property "Alternatives 75W" " VCB4812SBO-75WR3"
			(at 297.18 208.28 0)
			(effects
				(font
					(size 1.27 1.27)
				)
				(justify left)
				(hide yes)
			)
		)
		(property "Alternatives 100W" "PKU4913DPIHS, VCB4812SBO-100WFR3"
			(at 297.18 210.82 0)
			(effects
				(font
					(size 1.27 1.27)
				)
				(justify left)
				(hide yes)
			)
		)
		(property "Alternatives 120W" "PQC50-48-S12-O"
			(at 297.18 213.36 0)
			(effects
				(font
					(size 1.27 1.27)
				)
				(justify left)
				(hide yes)
			)
		)
		(pin "1"
		)
		(pin "2"
		)
		(pin "3"
		)
		(pin "4"
		)
		(pin "5"
		)
		(pin "6"
		)
		(pin "7"
		)
		(pin "8"
		)
		(instances
			(project "jetson-orin-baseboard"
				(path ""
					(reference "U23")
					(unit 1)
				)
			)
		)
	)
	(symbol
		(lib_id "antmicropower:GNDD")
		(at 162.56 228.6 0)
		(unit 1)
		(exclude_from_sim no)
		(in_bom yes)
		(on_board yes)
		(dnp no)
		(property "Reference" "#PWR0137"
			(at 162.56 234.95 0)
			(effects
				(font
					(size 1.27 1.27)
				)
				(justify left bottom)
				(hide yes)
			)
		)
		(property "Value" "GNDD"
			(at 162.56 231.775 0)
			(effects
				(font
					(size 1.27 1.27)
					(thickness 0.15)
				)
			)
		)
		(property "Footprint" ""
			(at 177.8 238.76 0)
			(effects
				(font
					(size 1.27 1.27)
					(thickness 0.15)
				)
				(justify left bottom)
				(hide yes)
			)
		)
		(property "Datasheet" ""
			(at 177.8 241.3 0)
			(effects
				(font
					(size 1.27 1.27)
					(thickness 0.15)
				)
				(justify left bottom)
				(hide yes)
			)
		)
		(property "Description" ""
			(at 162.56 228.6 0)
			(effects
				(font
					(size 1.27 1.27)
				)
				(hide yes)
			)
		)
		(property "Author" "Antmicro"
			(at 177.8 236.22 0)
			(effects
				(font
					(size 1.27 1.27)
					(thickness 0.15)
				)
				(justify left bottom)
				(hide yes)
			)
		)
		(property "License" "Apache-2.0"
			(at 177.8 238.76 0)
			(effects
				(font
					(size 1.27 1.27)
					(thickness 0.15)
				)
				(justify left bottom)
				(hide yes)
			)
		)
		(pin "1"
		)
		(instances
			(project "jetson-orin-baseboard"
				(path ""
					(reference "#PWR0137")
					(unit 1)
				)
			)
		)
	)
	(symbol
		(lib_id "antmicroDiodesRectifiersSingle:CD-MMBL110S")
		(at 53.34 198.12 0)
		(unit 1)
		(exclude_from_sim no)
		(in_bom yes)
		(on_board yes)
		(dnp no)
		(property "Reference" "D13"
			(at 62.23 193.04 0)
			(effects
				(font
					(size 1.27 1.27)
				)
			)
		)
		(property "Value" "CD-MMBL110S"
			(at 80.01 210.82 0)
			(effects
				(font
					(size 1.27 1.27)
					(thickness 0.15)
				)
				(justify left bottom)
				(hide yes)
			)
		)
		(property "Footprint" "antmicro-footprints:DFN3538"
			(at 80.01 205.74 0)
			(effects
				(font
					(size 1.27 1.27)
					(thickness 0.15)
				)
				(justify left bottom)
				(hide yes)
			)
		)
		(property "Datasheet" "https://www.bourns.com/docs/product-datasheets/CD-MMBL110S.pdf"
			(at 80.01 208.28 0)
			(effects
				(font
					(size 1.27 1.27)
					(thickness 0.15)
				)
				(justify left bottom)
				(hide yes)
			)
		)
		(property "Description" ""
			(at 53.34 198.12 0)
			(effects
				(font
					(size 1.27 1.27)
				)
				(hide yes)
			)
		)
		(property "MPN" "CD-MMBL110S"
			(at 62.23 195.58 0)
			(effects
				(font
					(size 1.27 1.27)
					(thickness 0.15)
				)
			)
		)
		(property "Manufacturer" "Bourns"
			(at 80.01 213.36 0)
			(effects
				(font
					(size 1.27 1.27)
					(thickness 0.15)
				)
				(justify left bottom)
				(hide yes)
			)
		)
		(property "Author" "Antmicro"
			(at 80.01 215.9 0)
			(effects
				(font
					(size 1.27 1.27)
					(thickness 0.15)
				)
				(justify left bottom)
				(hide yes)
			)
		)
		(property "License" "Apache-2.0"
			(at 80.01 218.44 0)
			(effects
				(font
					(size 1.27 1.27)
					(thickness 0.15)
				)
				(justify left bottom)
				(hide yes)
			)
		)
		(pin "1"
		)
		(pin "2"
		)
		(pin "3"
		)
		(pin "4"
		)
		(instances
			(project "jetson-orin-baseboard"
				(path ""
					(reference "D13")
					(unit 1)
				)
			)
		)
	)
	(symbol
		(lib_id "antmicroResistors0402:R_10k_0402")
		(at 175.26 213.36 180)
		(unit 1)
		(exclude_from_sim no)
		(in_bom yes)
		(on_board yes)
		(dnp no)
		(property "Reference" "R148"
			(at 175.26 212.725 0)
			(effects
				(font
					(size 1.27 1.27)
				)
				(justify right top)
			)
		)
		(property "Value" "R_10k_0402"
			(at 154.94 200.66 0)
			(effects
				(font
					(size 1.27 1.27)
					(thickness 0.15)
				)
				(justify left bottom)
				(hide yes)
			)
		)
		(property "Footprint" "antmicro-footprints:R_0402_1005Metric"
			(at 154.94 198.12 0)
			(effects
				(font
					(size 1.27 1.27)
					(thickness 0.15)
				)
				(justify left bottom)
				(hide yes)
			)
		)
		(property "Datasheet" "https://www.bourns.com/docs/product-datasheets/cr.pdf"
			(at 154.94 195.58 0)
			(effects
				(font
					(size 1.27 1.27)
					(thickness 0.15)
				)
				(justify left bottom)
				(hide yes)
			)
		)
		(property "Description" ""
			(at 175.26 213.36 0)
			(effects
				(font
					(size 1.27 1.27)
				)
				(hide yes)
			)
		)
		(property "Manufacturer" "Bourns"
			(at 154.94 190.5 0)
			(effects
				(font
					(size 1.27 1.27)
					(thickness 0.15)
				)
				(justify left bottom)
				(hide yes)
			)
		)
		(property "MPN" "CR0402-FX-1002GLF"
			(at 154.94 193.04 0)
			(effects
				(font
					(size 1.27 1.27)
					(thickness 0.15)
				)
				(justify left bottom)
				(hide yes)
			)
		)
		(property "Val" "10k"
			(at 166.37 212.725 0)
			(effects
				(font
					(size 1.27 1.27)
					(thickness 0.15)
				)
				(justify right top)
			)
		)
		(property "License" "Apache-2.0"
			(at 154.94 187.96 0)
			(effects
				(font
					(size 1.27 1.27)
					(thickness 0.15)
				)
				(justify left bottom)
				(hide yes)
			)
		)
		(property "Author" "Antmicro"
			(at 154.94 185.42 0)
			(effects
				(font
					(size 1.27 1.27)
					(thickness 0.15)
				)
				(justify left bottom)
				(hide yes)
			)
		)
		(property "Tolerance" "1%"
			(at 154.94 203.2 0)
			(effects
				(font
					(size 1.27 1.27)
				)
				(justify left bottom)
				(hide yes)
			)
		)
		(pin "1"
		)
		(pin "2"
		)
		(instances
			(project "jetson-orin-baseboard"
				(path ""
					(reference "R148")
					(unit 1)
				)
			)
		)
	)
	(symbol
		(lib_id "antmicroResistors0402:R_470k_0402")
		(at 257.81 190.5 90)
		(unit 1)
		(exclude_from_sim no)
		(in_bom yes)
		(on_board yes)
		(dnp no)
		(property "Reference" "R198"
			(at 259.08 186.69 90)
			(effects
				(font
					(size 1.27 1.27)
				)
				(justify right)
			)
		)
		(property "Value" "R_470k_0402"
			(at 270.51 170.18 0)
			(effects
				(font
					(size 1.27 1.27)
					(thickness 0.15)
				)
				(justify left bottom)
				(hide yes)
			)
		)
		(property "Footprint" "antmicro-footprints:R_0402_1005Metric"
			(at 273.05 170.18 0)
			(effects
				(font
					(size 1.27 1.27)
					(thickness 0.15)
				)
				(justify left bottom)
				(hide yes)
			)
		)
		(property "Datasheet" "https://www.bourns.com/docs/product-datasheets/cr.pdf"
			(at 275.59 170.18 0)
			(effects
				(font
					(size 1.27 1.27)
					(thickness 0.15)
				)
				(justify left bottom)
				(hide yes)
			)
		)
		(property "Description" ""
			(at 257.81 190.5 0)
			(effects
				(font
					(size 1.27 1.27)
				)
				(hide yes)
			)
		)
		(property "Manufacturer" "Bourns"
			(at 280.67 170.18 0)
			(effects
				(font
					(size 1.27 1.27)
					(thickness 0.15)
				)
				(justify left bottom)
				(hide yes)
			)
		)
		(property "MPN" "CR0402-FX-4703GLF"
			(at 278.13 170.18 0)
			(effects
				(font
					(size 1.27 1.27)
					(thickness 0.15)
				)
				(justify left bottom)
				(hide yes)
			)
		)
		(property "Val" "470k"
			(at 259.08 189.23 90)
			(effects
				(font
					(size 1.27 1.27)
					(thickness 0.15)
				)
				(justify right)
			)
		)
		(property "License" "Apache-2.0"
			(at 283.21 170.18 0)
			(effects
				(font
					(size 1.27 1.27)
					(thickness 0.15)
				)
				(justify left bottom)
				(hide yes)
			)
		)
		(property "Author" "Antmicro"
			(at 285.75 170.18 0)
			(effects
				(font
					(size 1.27 1.27)
					(thickness 0.15)
				)
				(justify left bottom)
				(hide yes)
			)
		)
		(property "Tolerance" "1%"
			(at 267.97 170.18 0)
			(effects
				(font
					(size 1.27 1.27)
				)
				(justify left bottom)
				(hide yes)
			)
		)
		(pin "1"
		)
		(pin "2"
		)
		(instances
			(project "jetson-orin-baseboard"
				(path ""
					(reference "R198")
					(unit 1)
				)
			)
		)
	)
	(symbol
		(lib_id "antmicropower:GNDD")
		(at 231.14 218.44 0)
		(unit 1)
		(exclude_from_sim no)
		(in_bom yes)
		(on_board yes)
		(dnp no)
		(property "Reference" "#PWR0141"
			(at 231.14 224.79 0)
			(effects
				(font
					(size 1.27 1.27)
				)
				(justify left bottom)
				(hide yes)
			)
		)
		(property "Value" "GNDD"
			(at 231.14 221.615 0)
			(effects
				(font
					(size 1.27 1.27)
					(thickness 0.15)
				)
			)
		)
		(property "Footprint" ""
			(at 246.38 228.6 0)
			(effects
				(font
					(size 1.27 1.27)
					(thickness 0.15)
				)
				(justify left bottom)
				(hide yes)
			)
		)
		(property "Datasheet" ""
			(at 246.38 231.14 0)
			(effects
				(font
					(size 1.27 1.27)
					(thickness 0.15)
				)
				(justify left bottom)
				(hide yes)
			)
		)
		(property "Description" ""
			(at 231.14 218.44 0)
			(effects
				(font
					(size 1.27 1.27)
				)
				(hide yes)
			)
		)
		(property "Author" "Antmicro"
			(at 246.38 226.06 0)
			(effects
				(font
					(size 1.27 1.27)
					(thickness 0.15)
				)
				(justify left bottom)
				(hide yes)
			)
		)
		(property "License" "Apache-2.0"
			(at 246.38 228.6 0)
			(effects
				(font
					(size 1.27 1.27)
					(thickness 0.15)
				)
				(justify left bottom)
				(hide yes)
			)
		)
		(pin "1"
		)
		(instances
			(project "jetson-orin-baseboard"
				(path ""
					(reference "#PWR0141")
					(unit 1)
				)
			)
		)
	)
	(symbol
		(lib_id "antmicropower:+3V3")
		(at 209.55 72.39 0)
		(unit 1)
		(exclude_from_sim no)
		(in_bom yes)
		(on_board yes)
		(dnp no)
		(property "Reference" "#PWR0142"
			(at 209.55 76.2 0)
			(effects
				(font
					(size 1.27 1.27)
				)
				(justify left bottom)
				(hide yes)
			)
		)
		(property "Value" "+3V3"
			(at 206.375 68.58 0)
			(effects
				(font
					(size 1.27 1.27)
					(thickness 0.15)
				)
				(justify left)
			)
		)
		(property "Footprint" ""
			(at 224.79 80.01 0)
			(effects
				(font
					(size 1.27 1.27)
					(thickness 0.15)
				)
				(justify left bottom)
				(hide yes)
			)
		)
		(property "Datasheet" ""
			(at 224.79 82.55 0)
			(effects
				(font
					(size 1.27 1.27)
					(thickness 0.15)
				)
				(justify left bottom)
				(hide yes)
			)
		)
		(property "Description" ""
			(at 209.55 72.39 0)
			(effects
				(font
					(size 1.27 1.27)
				)
				(hide yes)
			)
		)
		(property "Author" "Antmicro"
			(at 224.79 74.93 0)
			(effects
				(font
					(size 1.27 1.27)
					(thickness 0.15)
				)
				(justify left bottom)
				(hide yes)
			)
		)
		(property "License" "Apache-2.0"
			(at 224.79 77.47 0)
			(effects
				(font
					(size 1.27 1.27)
					(thickness 0.15)
				)
				(justify left bottom)
				(hide yes)
			)
		)
		(pin "1"
		)
		(instances
			(project "jetson-orin-baseboard"
				(path ""
					(reference "#PWR0142")
					(unit 1)
				)
			)
		)
	)
	(symbol
		(lib_id "antmicroResistors0402:R_10k_0402")
		(at 168.91 189.23 90)
		(unit 1)
		(exclude_from_sim no)
		(in_bom no)
		(on_board yes)
		(dnp yes)
		(property "Reference" "R149"
			(at 170.18 185.42 90)
			(effects
				(font
					(size 1.27 1.27)
				)
				(justify right)
			)
		)
		(property "Value" "R_10k_0402"
			(at 181.61 168.91 0)
			(effects
				(font
					(size 1.27 1.27)
					(thickness 0.15)
				)
				(justify left bottom)
				(hide yes)
			)
		)
		(property "Footprint" "antmicro-footprints:R_0402_1005Metric"
			(at 184.15 168.91 0)
			(effects
				(font
					(size 1.27 1.27)
					(thickness 0.15)
				)
				(justify left bottom)
				(hide yes)
			)
		)
		(property "Datasheet" "https://www.bourns.com/docs/product-datasheets/cr.pdf"
			(at 186.69 168.91 0)
			(effects
				(font
					(size 1.27 1.27)
					(thickness 0.15)
				)
				(justify left bottom)
				(hide yes)
			)
		)
		(property "Description" ""
			(at 168.91 189.23 0)
			(effects
				(font
					(size 1.27 1.27)
				)
				(hide yes)
			)
		)
		(property "Manufacturer" "Bourns"
			(at 191.77 168.91 0)
			(effects
				(font
					(size 1.27 1.27)
					(thickness 0.15)
				)
				(justify left bottom)
				(hide yes)
			)
		)
		(property "MPN" "CR0402-FX-1002GLF"
			(at 189.23 168.91 0)
			(effects
				(font
					(size 1.27 1.27)
					(thickness 0.15)
				)
				(justify left bottom)
				(hide yes)
			)
		)
		(property "Val" "10k"
			(at 170.18 187.96 90)
			(effects
				(font
					(size 1.27 1.27)
					(thickness 0.15)
				)
				(justify right)
			)
		)
		(property "License" "Apache-2.0"
			(at 194.31 168.91 0)
			(effects
				(font
					(size 1.27 1.27)
					(thickness 0.15)
				)
				(justify left bottom)
				(hide yes)
			)
		)
		(property "Author" "Antmicro"
			(at 196.85 168.91 0)
			(effects
				(font
					(size 1.27 1.27)
					(thickness 0.15)
				)
				(justify left bottom)
				(hide yes)
			)
		)
		(property "Tolerance" "1%"
			(at 179.07 168.91 0)
			(effects
				(font
					(size 1.27 1.27)
				)
				(justify left bottom)
				(hide yes)
			)
		)
		(pin "1"
		)
		(pin "2"
		)
		(instances
			(project "jetson-orin-baseboard"
				(path ""
					(reference "R149")
					(unit 1)
				)
			)
		)
	)
	(symbol
		(lib_id "antmicroResistors0402:R_200R_0402")
		(at 218.44 81.28 0)
		(mirror x)
		(unit 1)
		(exclude_from_sim no)
		(in_bom yes)
		(on_board yes)
		(dnp no)
		(property "Reference" "R152"
			(at 223.52 80.645 0)
			(effects
				(font
					(size 1.27 1.27)
				)
				(justify left top)
			)
		)
		(property "Value" "R_200R_0402"
			(at 238.76 68.58 0)
			(effects
				(font
					(size 1.27 1.27)
					(thickness 0.15)
				)
				(justify left bottom)
				(hide yes)
			)
		)
		(property "Footprint" "antmicro-footprints:R_0402_1005Metric"
			(at 238.76 66.04 0)
			(effects
				(font
					(size 1.27 1.27)
					(thickness 0.15)
				)
				(justify left bottom)
				(hide yes)
			)
		)
		(property "Datasheet" "https://www.bourns.com/docs/product-datasheets/cr.pdf"
			(at 238.76 63.5 0)
			(effects
				(font
					(size 1.27 1.27)
					(thickness 0.15)
				)
				(justify left bottom)
				(hide yes)
			)
		)
		(property "Description" ""
			(at 218.44 81.28 0)
			(effects
				(font
					(size 1.27 1.27)
				)
				(hide yes)
			)
		)
		(property "Manufacturer" "Bourns"
			(at 238.76 58.42 0)
			(effects
				(font
					(size 1.27 1.27)
					(thickness 0.15)
				)
				(justify left bottom)
				(hide yes)
			)
		)
		(property "MPN" "CR0402-FX-2000GLF"
			(at 238.76 60.96 0)
			(effects
				(font
					(size 1.27 1.27)
					(thickness 0.15)
				)
				(justify left bottom)
				(hide yes)
			)
		)
		(property "Val" "200R"
			(at 213.36 80.645 0)
			(effects
				(font
					(size 1.27 1.27)
					(thickness 0.15)
				)
				(justify left top)
			)
		)
		(property "License" "Apache-2.0"
			(at 238.76 55.88 0)
			(effects
				(font
					(size 1.27 1.27)
					(thickness 0.15)
				)
				(justify left bottom)
				(hide yes)
			)
		)
		(property "Author" "Antmicro"
			(at 238.76 53.34 0)
			(effects
				(font
					(size 1.27 1.27)
					(thickness 0.15)
				)
				(justify left bottom)
				(hide yes)
			)
		)
		(property "Tolerance" "1%"
			(at 238.76 71.12 0)
			(effects
				(font
					(size 1.27 1.27)
				)
				(justify left bottom)
				(hide yes)
			)
		)
		(pin "1"
		)
		(pin "2"
		)
		(instances
			(project "jetson-orin-baseboard"
				(path ""
					(reference "R152")
					(unit 1)
				)
			)
		)
	)
	(symbol
		(lib_id "antmicropower:GNDD")
		(at 200.66 218.44 0)
		(unit 1)
		(exclude_from_sim no)
		(in_bom yes)
		(on_board yes)
		(dnp no)
		(fields_autoplaced yes)
		(property "Reference" "#PWR0138"
			(at 200.66 224.79 0)
			(effects
				(font
					(size 1.27 1.27)
				)
				(justify left bottom)
				(hide yes)
			)
		)
		(property "Value" "GNDD"
			(at 200.66 221.615 0)
			(effects
				(font
					(size 1.27 1.27)
					(thickness 0.15)
				)
			)
		)
		(property "Footprint" ""
			(at 215.9 228.6 0)
			(effects
				(font
					(size 1.27 1.27)
					(thickness 0.15)
				)
				(justify left bottom)
				(hide yes)
			)
		)
		(property "Datasheet" ""
			(at 215.9 231.14 0)
			(effects
				(font
					(size 1.27 1.27)
					(thickness 0.15)
				)
				(justify left bottom)
				(hide yes)
			)
		)
		(property "Description" ""
			(at 200.66 218.44 0)
			(effects
				(font
					(size 1.27 1.27)
				)
				(hide yes)
			)
		)
		(property "Author" "Antmicro"
			(at 215.9 226.06 0)
			(effects
				(font
					(size 1.27 1.27)
					(thickness 0.15)
				)
				(justify left bottom)
				(hide yes)
			)
		)
		(property "License" "Apache-2.0"
			(at 215.9 228.6 0)
			(effects
				(font
					(size 1.27 1.27)
					(thickness 0.15)
				)
				(justify left bottom)
				(hide yes)
			)
		)
		(pin "1"
		)
		(instances
			(project "jetson-orin-baseboard"
				(path ""
					(reference "#PWR0138")
					(unit 1)
				)
			)
		)
	)
	(symbol
		(lib_id "antmicroResistors0402:R_470k_0402")
		(at 297.18 190.5 90)
		(unit 1)
		(exclude_from_sim no)
		(in_bom no)
		(on_board yes)
		(dnp yes)
		(property "Reference" "R199"
			(at 298.45 186.69 90)
			(effects
				(font
					(size 1.27 1.27)
				)
				(justify right)
			)
		)
		(property "Value" "R_470k_0402"
			(at 309.88 170.18 0)
			(effects
				(font
					(size 1.27 1.27)
					(thickness 0.15)
				)
				(justify left bottom)
				(hide yes)
			)
		)
		(property "Footprint" "antmicro-footprints:R_0402_1005Metric"
			(at 312.42 170.18 0)
			(effects
				(font
					(size 1.27 1.27)
					(thickness 0.15)
				)
				(justify left bottom)
				(hide yes)
			)
		)
		(property "Datasheet" "https://www.bourns.com/docs/product-datasheets/cr.pdf"
			(at 314.96 170.18 0)
			(effects
				(font
					(size 1.27 1.27)
					(thickness 0.15)
				)
				(justify left bottom)
				(hide yes)
			)
		)
		(property "Description" ""
			(at 297.18 190.5 0)
			(effects
				(font
					(size 1.27 1.27)
				)
				(hide yes)
			)
		)
		(property "Manufacturer" "Bourns"
			(at 320.04 170.18 0)
			(effects
				(font
					(size 1.27 1.27)
					(thickness 0.15)
				)
				(justify left bottom)
				(hide yes)
			)
		)
		(property "MPN" "CR0402-FX-4703GLF"
			(at 317.5 170.18 0)
			(effects
				(font
					(size 1.27 1.27)
					(thickness 0.15)
				)
				(justify left bottom)
				(hide yes)
			)
		)
		(property "Val" "470k"
			(at 298.45 189.23 90)
			(effects
				(font
					(size 1.27 1.27)
					(thickness 0.15)
				)
				(justify right)
			)
		)
		(property "License" "Apache-2.0"
			(at 322.58 170.18 0)
			(effects
				(font
					(size 1.27 1.27)
					(thickness 0.15)
				)
				(justify left bottom)
				(hide yes)
			)
		)
		(property "Author" "Antmicro"
			(at 325.12 170.18 0)
			(effects
				(font
					(size 1.27 1.27)
					(thickness 0.15)
				)
				(justify left bottom)
				(hide yes)
			)
		)
		(property "Tolerance" "1%"
			(at 307.34 170.18 0)
			(effects
				(font
					(size 1.27 1.27)
				)
				(justify left bottom)
				(hide yes)
			)
		)
		(pin "1"
		)
		(pin "2"
		)
		(instances
			(project "jetson-orin-baseboard"
				(path ""
					(reference "R199")
					(unit 1)
				)
			)
		)
	)
	(symbol
		(lib_id "antmicroResistors0402:R_200R_0402")
		(at 218.44 76.2 0)
		(mirror x)
		(unit 1)
		(exclude_from_sim no)
		(in_bom yes)
		(on_board yes)
		(dnp no)
		(property "Reference" "R151"
			(at 223.52 75.565 0)
			(effects
				(font
					(size 1.27 1.27)
				)
				(justify left top)
			)
		)
		(property "Value" "R_200R_0402"
			(at 238.76 63.5 0)
			(effects
				(font
					(size 1.27 1.27)
					(thickness 0.15)
				)
				(justify left bottom)
				(hide yes)
			)
		)
		(property "Footprint" "antmicro-footprints:R_0402_1005Metric"
			(at 238.76 60.96 0)
			(effects
				(font
					(size 1.27 1.27)
					(thickness 0.15)
				)
				(justify left bottom)
				(hide yes)
			)
		)
		(property "Datasheet" "https://www.bourns.com/docs/product-datasheets/cr.pdf"
			(at 238.76 58.42 0)
			(effects
				(font
					(size 1.27 1.27)
					(thickness 0.15)
				)
				(justify left bottom)
				(hide yes)
			)
		)
		(property "Description" ""
			(at 218.44 76.2 0)
			(effects
				(font
					(size 1.27 1.27)
				)
				(hide yes)
			)
		)
		(property "Manufacturer" "Bourns"
			(at 238.76 53.34 0)
			(effects
				(font
					(size 1.27 1.27)
					(thickness 0.15)
				)
				(justify left bottom)
				(hide yes)
			)
		)
		(property "MPN" "CR0402-FX-2000GLF"
			(at 238.76 55.88 0)
			(effects
				(font
					(size 1.27 1.27)
					(thickness 0.15)
				)
				(justify left bottom)
				(hide yes)
			)
		)
		(property "Val" "200R"
			(at 213.36 75.565 0)
			(effects
				(font
					(size 1.27 1.27)
					(thickness 0.15)
				)
				(justify left top)
			)
		)
		(property "License" "Apache-2.0"
			(at 238.76 50.8 0)
			(effects
				(font
					(size 1.27 1.27)
					(thickness 0.15)
				)
				(justify left bottom)
				(hide yes)
			)
		)
		(property "Author" "Antmicro"
			(at 238.76 48.26 0)
			(effects
				(font
					(size 1.27 1.27)
					(thickness 0.15)
				)
				(justify left bottom)
				(hide yes)
			)
		)
		(property "Tolerance" "1%"
			(at 238.76 66.04 0)
			(effects
				(font
					(size 1.27 1.27)
				)
				(justify left bottom)
				(hide yes)
			)
		)
		(pin "1"
		)
		(pin "2"
		)
		(instances
			(project "jetson-orin-baseboard"
				(path ""
					(reference "R151")
					(unit 1)
				)
			)
		)
	)
	(symbol
		(lib_id "antmicroCapacitors0402:C_100n_0402")
		(at 369.57 187.96 90)
		(mirror x)
		(unit 1)
		(exclude_from_sim no)
		(in_bom yes)
		(on_board yes)
		(dnp no)
		(fields_autoplaced yes)
		(property "Reference" "C52"
			(at 372.11 189.2363 90)
			(effects
				(font
					(size 1.27 1.27)
				)
				(justify right)
			)
		)
		(property "Value" "C_100n_0402"
			(at 379.73 208.28 0)
			(effects
				(font
					(size 1.27 1.27)
					(thickness 0.15)
				)
				(justify left bottom)
				(hide yes)
			)
		)
		(property "Footprint" "antmicro-footprints:C_0402_1005Metric"
			(at 382.27 208.28 0)
			(effects
				(font
					(size 1.27 1.27)
					(thickness 0.15)
				)
				(justify left bottom)
				(hide yes)
			)
		)
		(property "Datasheet" "https://www.murata.com/products/productdetail?partno=GRM155R61H104KE14%23"
			(at 384.81 208.28 0)
			(effects
				(font
					(size 1.27 1.27)
					(thickness 0.15)
				)
				(justify left bottom)
				(hide yes)
			)
		)
		(property "Description" ""
			(at 369.57 187.96 0)
			(effects
				(font
					(size 1.27 1.27)
				)
				(hide yes)
			)
		)
		(property "MPN" "GRM155R61H104KE14D"
			(at 387.35 208.28 0)
			(effects
				(font
					(size 1.27 1.27)
					(thickness 0.15)
				)
				(justify left bottom)
				(hide yes)
			)
		)
		(property "Manufacturer" "Murata"
			(at 389.89 208.28 0)
			(effects
				(font
					(size 1.27 1.27)
					(thickness 0.15)
				)
				(justify left bottom)
				(hide yes)
			)
		)
		(property "Val" "100n"
			(at 372.11 191.7763 90)
			(effects
				(font
					(size 1.27 1.27)
					(thickness 0.15)
				)
				(justify right)
			)
		)
		(property "License" "Apache-2.0"
			(at 392.43 208.28 0)
			(effects
				(font
					(size 1.27 1.27)
					(thickness 0.15)
				)
				(justify left bottom)
				(hide yes)
			)
		)
		(property "Author" "Antmicro"
			(at 394.97 208.28 0)
			(effects
				(font
					(size 1.27 1.27)
					(thickness 0.15)
				)
				(justify left bottom)
				(hide yes)
			)
		)
		(property "Voltage" "50V"
			(at 397.51 208.28 0)
			(effects
				(font
					(size 1.27 1.27)
				)
				(justify left bottom)
				(hide yes)
			)
		)
		(property "Dielectric" "X5R"
			(at 400.05 208.28 0)
			(effects
				(font
					(size 1.27 1.27)
				)
				(justify left bottom)
				(hide yes)
			)
		)
		(pin "1"
		)
		(pin "2"
		)
		(instances
			(project "jetson-orin-baseboard"
				(path ""
					(reference "C52")
					(unit 1)
				)
			)
		)
	)
	(symbol
		(lib_id "antmicropower:GND")
		(at 313.69 237.49 0)
		(unit 1)
		(exclude_from_sim no)
		(in_bom yes)
		(on_board yes)
		(dnp no)
		(property "Reference" "#PWR0147"
			(at 313.69 243.84 0)
			(effects
				(font
					(size 1.27 1.27)
				)
				(justify left bottom)
				(hide yes)
			)
		)
		(property "Value" "GND"
			(at 313.69 241.3 0)
			(effects
				(font
					(size 1.27 1.27)
					(thickness 0.15)
				)
			)
		)
		(property "Footprint" ""
			(at 322.58 245.11 0)
			(effects
				(font
					(size 1.27 1.27)
					(thickness 0.15)
				)
				(justify left bottom)
				(hide yes)
			)
		)
		(property "Datasheet" ""
			(at 322.58 250.19 0)
			(effects
				(font
					(size 1.27 1.27)
					(thickness 0.15)
				)
				(justify left bottom)
				(hide yes)
			)
		)
		(property "Description" ""
			(at 313.69 237.49 0)
			(effects
				(font
					(size 1.27 1.27)
				)
				(hide yes)
			)
		)
		(property "Author" "Antmicro"
			(at 322.58 245.11 0)
			(effects
				(font
					(size 1.27 1.27)
					(thickness 0.15)
				)
				(justify left bottom)
				(hide yes)
			)
		)
		(property "License" "Apache-2.0"
			(at 322.58 247.65 0)
			(effects
				(font
					(size 1.27 1.27)
					(thickness 0.15)
				)
				(justify left bottom)
				(hide yes)
			)
		)
		(pin "1"
		)
		(instances
			(project "jetson-orin-baseboard"
				(path ""
					(reference "#PWR0147")
					(unit 1)
				)
			)
		)
	)
	(symbol
		(lib_id "antmicropower:GNDD")
		(at 241.3 218.44 0)
		(unit 1)
		(exclude_from_sim no)
		(in_bom yes)
		(on_board yes)
		(dnp no)
		(property "Reference" "#PWR0144"
			(at 241.3 224.79 0)
			(effects
				(font
					(size 1.27 1.27)
				)
				(justify left bottom)
				(hide yes)
			)
		)
		(property "Value" "GNDD"
			(at 241.3 221.615 0)
			(effects
				(font
					(size 1.27 1.27)
					(thickness 0.15)
				)
			)
		)
		(property "Footprint" ""
			(at 256.54 228.6 0)
			(effects
				(font
					(size 1.27 1.27)
					(thickness 0.15)
				)
				(justify left bottom)
				(hide yes)
			)
		)
		(property "Datasheet" ""
			(at 256.54 231.14 0)
			(effects
				(font
					(size 1.27 1.27)
					(thickness 0.15)
				)
				(justify left bottom)
				(hide yes)
			)
		)
		(property "Description" ""
			(at 241.3 218.44 0)
			(effects
				(font
					(size 1.27 1.27)
				)
				(hide yes)
			)
		)
		(property "Author" "Antmicro"
			(at 256.54 226.06 0)
			(effects
				(font
					(size 1.27 1.27)
					(thickness 0.15)
				)
				(justify left bottom)
				(hide yes)
			)
		)
		(property "License" "Apache-2.0"
			(at 256.54 228.6 0)
			(effects
				(font
					(size 1.27 1.27)
					(thickness 0.15)
				)
				(justify left bottom)
				(hide yes)
			)
		)
		(pin "1"
		)
		(instances
			(project "jetson-orin-baseboard"
				(path ""
					(reference "#PWR0144")
					(unit 1)
				)
			)
		)
	)
	(symbol
		(lib_id "antmicroResistors0402:R_100k_0402")
		(at 297.18 203.2 90)
		(unit 1)
		(exclude_from_sim no)
		(in_bom no)
		(on_board yes)
		(dnp yes)
		(property "Reference" "R229"
			(at 298.45 199.39 90)
			(effects
				(font
					(size 1.27 1.27)
				)
				(justify right)
			)
		)
		(property "Value" "R_100k_0402"
			(at 309.88 182.88 0)
			(effects
				(font
					(size 1.27 1.27)
					(thickness 0.15)
				)
				(justify left bottom)
				(hide yes)
			)
		)
		(property "Footprint" "antmicro-footprints:R_0402_1005Metric"
			(at 312.42 182.88 0)
			(effects
				(font
					(size 1.27 1.27)
					(thickness 0.15)
				)
				(justify left bottom)
				(hide yes)
			)
		)
		(property "Datasheet" "https://www.bourns.com/docs/product-datasheets/cr.pdf"
			(at 314.96 182.88 0)
			(effects
				(font
					(size 1.27 1.27)
					(thickness 0.15)
				)
				(justify left bottom)
				(hide yes)
			)
		)
		(property "Description" ""
			(at 297.18 203.2 0)
			(effects
				(font
					(size 1.27 1.27)
				)
				(hide yes)
			)
		)
		(property "Manufacturer" "Bourns"
			(at 320.04 182.88 0)
			(effects
				(font
					(size 1.27 1.27)
					(thickness 0.15)
				)
				(justify left bottom)
				(hide yes)
			)
		)
		(property "MPN" "CR0402-FX-1003GLF"
			(at 317.5 182.88 0)
			(effects
				(font
					(size 1.27 1.27)
					(thickness 0.15)
				)
				(justify left bottom)
				(hide yes)
			)
		)
		(property "Val" "100k"
			(at 298.45 201.93 90)
			(effects
				(font
					(size 1.27 1.27)
					(thickness 0.15)
				)
				(justify right)
			)
		)
		(property "License" "Apache-2.0"
			(at 322.58 182.88 0)
			(effects
				(font
					(size 1.27 1.27)
					(thickness 0.15)
				)
				(justify left bottom)
				(hide yes)
			)
		)
		(property "Author" "Antmicro"
			(at 325.12 182.88 0)
			(effects
				(font
					(size 1.27 1.27)
					(thickness 0.15)
				)
				(justify left bottom)
				(hide yes)
			)
		)
		(property "Tolerance" "1%"
			(at 307.34 182.88 0)
			(effects
				(font
					(size 1.27 1.27)
				)
				(justify left bottom)
				(hide yes)
			)
		)
		(pin "1"
		)
		(pin "2"
		)
		(instances
			(project "jetson-orin-baseboard"
				(path ""
					(reference "R229")
					(unit 1)
				)
			)
		)
	)
	(symbol
		(lib_id "antmicroCapacitorsmisc:C_47u_16V_1206")
		(at 359.41 193.04 90)
		(unit 1)
		(exclude_from_sim no)
		(in_bom yes)
		(on_board yes)
		(dnp no)
		(fields_autoplaced yes)
		(property "Reference" "C85"
			(at 361.95 187.9536 90)
			(effects
				(font
					(size 1.27 1.27)
				)
				(justify right)
			)
		)
		(property "Value" "C_47u_16V_1206"
			(at 369.57 172.72 0)
			(effects
				(font
					(size 1.27 1.27)
					(thickness 0.15)
				)
				(justify left bottom)
				(hide yes)
			)
		)
		(property "Footprint" "antmicro-footprints:C_1206_3216Metric"
			(at 372.11 172.72 0)
			(effects
				(font
					(size 1.27 1.27)
					(thickness 0.15)
				)
				(justify left bottom)
				(hide yes)
			)
		)
		(property "Datasheet" "https://product.tdk.com/en/search/capacitor/ceramic/mlcc/info?part_no=C3216X5R1C476M160AB"
			(at 374.65 172.72 0)
			(effects
				(font
					(size 1.27 1.27)
					(thickness 0.15)
				)
				(justify left bottom)
				(hide yes)
			)
		)
		(property "Description" ""
			(at 359.41 193.04 0)
			(effects
				(font
					(size 1.27 1.27)
				)
				(hide yes)
			)
		)
		(property "Manufacturer" "TDK"
			(at 379.73 172.72 0)
			(effects
				(font
					(size 1.27 1.27)
					(thickness 0.15)
				)
				(justify left bottom)
				(hide yes)
			)
		)
		(property "MPN" "C3216X5R1C476M160AB"
			(at 377.19 172.72 0)
			(effects
				(font
					(size 1.27 1.27)
					(thickness 0.15)
				)
				(justify left bottom)
				(hide yes)
			)
		)
		(property "Val" "47u"
			(at 361.95 190.4936 90)
			(effects
				(font
					(size 1.27 1.27)
					(thickness 0.15)
				)
				(justify right)
			)
		)
		(property "License" "Apache-2.0"
			(at 382.27 172.72 0)
			(effects
				(font
					(size 1.27 1.27)
					(thickness 0.15)
				)
				(justify left bottom)
				(hide yes)
			)
		)
		(property "Author" "Antmicro"
			(at 384.81 172.72 0)
			(effects
				(font
					(size 1.27 1.27)
					(thickness 0.15)
				)
				(justify left bottom)
				(hide yes)
			)
		)
		(property "Voltage" "16V"
			(at 361.95 193.0336 90)
			(effects
				(font
					(size 1.27 1.27)
				)
				(justify right)
			)
		)
		(property "Dielectric" "X5R"
			(at 389.89 172.72 0)
			(effects
				(font
					(size 1.27 1.27)
				)
				(justify left bottom)
				(hide yes)
			)
		)
		(property "Public" "False"
			(at 392.43 172.72 0)
			(effects
				(font
					(size 1.27 1.27)
				)
				(justify left bottom)
				(hide yes)
			)
		)
		(pin "1"
		)
		(pin "2"
		)
		(instances
			(project "jetson-orin-baseboard"
				(path ""
					(reference "C85")
					(unit 1)
				)
			)
		)
	)
	(symbol
		(lib_id "antmicroCapacitorsmisc:C_22u_100V_2220")
		(at 210.82 204.47 90)
		(unit 1)
		(exclude_from_sim no)
		(in_bom yes)
		(on_board yes)
		(dnp no)
		(property "Reference" "C80"
			(at 212.725 199.39 90)
			(effects
				(font
					(size 1.27 1.27)
				)
				(justify right)
			)
		)
		(property "Value" "C_22u_100V_2220"
			(at 220.98 184.15 0)
			(effects
				(font
					(size 1.27 1.27)
					(thickness 0.15)
				)
				(justify left bottom)
				(hide yes)
			)
		)
		(property "Footprint" "antmicro-footprints:C_2220_5650Metric"
			(at 223.52 184.15 0)
			(effects
				(font
					(size 1.27 1.27)
					(thickness 0.15)
				)
				(justify left bottom)
				(hide yes)
			)
		)
		(property "Datasheet" "https://product.tdk.com/en/search/capacitor/ceramic/mlcc/info?part_no=C5750X7S2A226M280KB"
			(at 226.06 184.15 0)
			(effects
				(font
					(size 1.27 1.27)
					(thickness 0.15)
				)
				(justify left bottom)
				(hide yes)
			)
		)
		(property "Description" ""
			(at 210.82 204.47 0)
			(effects
				(font
					(size 1.27 1.27)
				)
				(hide yes)
			)
		)
		(property "Manufacturer" "TDK"
			(at 231.14 184.15 0)
			(effects
				(font
					(size 1.27 1.27)
					(thickness 0.15)
				)
				(justify left bottom)
				(hide yes)
			)
		)
		(property "MPN" "C5750X7S2A226M280KB"
			(at 228.6 184.15 0)
			(effects
				(font
					(size 1.27 1.27)
					(thickness 0.15)
				)
				(justify left bottom)
				(hide yes)
			)
		)
		(property "Val" "22u"
			(at 212.725 201.93 90)
			(effects
				(font
					(size 1.27 1.27)
					(thickness 0.15)
				)
				(justify right)
			)
		)
		(property "License" "Apache-2.0"
			(at 233.68 184.15 0)
			(effects
				(font
					(size 1.27 1.27)
					(thickness 0.15)
				)
				(justify left bottom)
				(hide yes)
			)
		)
		(property "Author" "Antmicro"
			(at 236.22 184.15 0)
			(effects
				(font
					(size 1.27 1.27)
					(thickness 0.15)
				)
				(justify left bottom)
				(hide yes)
			)
		)
		(property "Voltage" "100V"
			(at 212.725 204.47 90)
			(effects
				(font
					(size 1.27 1.27)
				)
				(justify right)
			)
		)
		(property "Dielectric" "X7S"
			(at 241.3 184.15 0)
			(effects
				(font
					(size 1.27 1.27)
				)
				(justify left bottom)
				(hide yes)
			)
		)
		(property "Public" "False"
			(at 243.84 184.15 0)
			(effects
				(font
					(size 1.27 1.27)
				)
				(justify left bottom)
				(hide yes)
			)
		)
		(pin "1"
		)
		(pin "2"
		)
		(instances
			(project "jetson-orin-baseboard"
				(path ""
					(reference "C80")
					(unit 1)
				)
			)
		)
	)
	(symbol
		(lib_id "antmicroPMICPowerDistributionSwitchesLoadDrivers:TPS2372-3RGWR")
		(at 138.43 193.04 0)
		(unit 1)
		(exclude_from_sim no)
		(in_bom yes)
		(on_board yes)
		(dnp no)
		(property "Reference" "U22"
			(at 149.225 186.69 0)
			(effects
				(font
					(size 1.27 1.27)
				)
			)
		)
		(property "Value" "TPS2372-3RGWR"
			(at 173.99 195.58 0)
			(effects
				(font
					(size 1.27 1.27)
					(thickness 0.15)
				)
				(justify left bottom)
				(hide yes)
			)
		)
		(property "Footprint" "antmicro-footprints:VQFN-20_5x5x1mm_P0.65mm"
			(at 173.99 198.12 0)
			(effects
				(font
					(size 1.27 1.27)
					(thickness 0.15)
				)
				(justify left bottom)
				(hide yes)
			)
		)
		(property "Datasheet" "https://www.ti.com/lit/ds/symlink/tps2372.pdf?ts=1679042478513&ref_url=https%253A%252F%252Fwww.google.com%252F"
			(at 173.99 200.66 0)
			(effects
				(font
					(size 1.27 1.27)
					(thickness 0.15)
				)
				(justify left bottom)
				(hide yes)
			)
		)
		(property "Description" ""
			(at 138.43 193.04 0)
			(effects
				(font
					(size 1.27 1.27)
				)
				(hide yes)
			)
		)
		(property "MPN" "TPS2372-3RGWR"
			(at 149.225 189.23 0)
			(effects
				(font
					(size 1.27 1.27)
					(thickness 0.15)
				)
			)
		)
		(property "Manufacturer" "Texas Instruments"
			(at 173.99 205.74 0)
			(effects
				(font
					(size 1.27 1.27)
					(thickness 0.15)
				)
				(justify left bottom)
				(hide yes)
			)
		)
		(property "Author" "Antmicro"
			(at 173.99 208.28 0)
			(effects
				(font
					(size 1.27 1.27)
					(thickness 0.15)
				)
				(justify left bottom)
				(hide yes)
			)
		)
		(property "License" "Apache-2.0"
			(at 173.99 210.82 0)
			(effects
				(font
					(size 1.27 1.27)
					(thickness 0.15)
				)
				(justify left bottom)
				(hide yes)
			)
		)
		(pin "1"
		)
		(pin "10"
		)
		(pin "11"
		)
		(pin "12"
		)
		(pin "13"
		)
		(pin "14"
		)
		(pin "15"
		)
		(pin "16"
		)
		(pin "17"
		)
		(pin "18"
		)
		(pin "19"
		)
		(pin "2"
		)
		(pin "20"
		)
		(pin "21"
		)
		(pin "3"
		)
		(pin "4"
		)
		(pin "5"
		)
		(pin "6"
		)
		(pin "7"
		)
		(pin "8"
		)
		(pin "9"
		)
		(instances
			(project "jetson-orin-baseboard"
				(path ""
					(reference "U22")
					(unit 1)
				)
			)
		)
	)
	(symbol
		(lib_id "antmicroCapacitors0402:C_100n_0402")
		(at 210.82 87.63 90)
		(mirror x)
		(unit 1)
		(exclude_from_sim no)
		(in_bom yes)
		(on_board yes)
		(dnp no)
		(fields_autoplaced yes)
		(property "Reference" "C78"
			(at 213.36 88.9063 90)
			(effects
				(font
					(size 1.27 1.27)
				)
				(justify right)
			)
		)
		(property "Value" "C_100n_0402"
			(at 220.98 107.95 0)
			(effects
				(font
					(size 1.27 1.27)
					(thickness 0.15)
				)
				(justify left bottom)
				(hide yes)
			)
		)
		(property "Footprint" "antmicro-footprints:C_0402_1005Metric"
			(at 223.52 107.95 0)
			(effects
				(font
					(size 1.27 1.27)
					(thickness 0.15)
				)
				(justify left bottom)
				(hide yes)
			)
		)
		(property "Datasheet" "https://www.murata.com/products/productdetail?partno=GRM155R61H104KE14%23"
			(at 226.06 107.95 0)
			(effects
				(font
					(size 1.27 1.27)
					(thickness 0.15)
				)
				(justify left bottom)
				(hide yes)
			)
		)
		(property "Description" ""
			(at 210.82 87.63 0)
			(effects
				(font
					(size 1.27 1.27)
				)
				(hide yes)
			)
		)
		(property "Manufacturer" "Murata"
			(at 231.14 107.95 0)
			(effects
				(font
					(size 1.27 1.27)
					(thickness 0.15)
				)
				(justify left bottom)
				(hide yes)
			)
		)
		(property "MPN" "GRM155R61H104KE14D"
			(at 228.6 107.95 0)
			(effects
				(font
					(size 1.27 1.27)
					(thickness 0.15)
				)
				(justify left bottom)
				(hide yes)
			)
		)
		(property "Val" "100n"
			(at 213.36 91.4463 90)
			(effects
				(font
					(size 1.27 1.27)
					(thickness 0.15)
				)
				(justify right)
			)
		)
		(property "License" "Apache-2.0"
			(at 233.68 107.95 0)
			(effects
				(font
					(size 1.27 1.27)
					(thickness 0.15)
				)
				(justify left bottom)
				(hide yes)
			)
		)
		(property "Author" "Antmicro"
			(at 236.22 107.95 0)
			(effects
				(font
					(size 1.27 1.27)
					(thickness 0.15)
				)
				(justify left bottom)
				(hide yes)
			)
		)
		(property "Voltage" "50V"
			(at 238.76 107.95 0)
			(effects
				(font
					(size 1.27 1.27)
				)
				(justify left bottom)
				(hide yes)
			)
		)
		(property "Dielectric" "X5R"
			(at 241.3 107.95 0)
			(effects
				(font
					(size 1.27 1.27)
				)
				(justify left bottom)
				(hide yes)
			)
		)
		(pin "1"
		)
		(pin "2"
		)
		(instances
			(project "jetson-orin-baseboard"
				(path ""
					(reference "C78")
					(unit 1)
				)
			)
		)
	)
	(symbol
		(lib_id "antmicroResistors0402:R_100k_0402")
		(at 257.81 215.9 90)
		(unit 1)
		(exclude_from_sim no)
		(in_bom yes)
		(on_board yes)
		(dnp no)
		(property "Reference" "R185"
			(at 259.08 212.09 90)
			(effects
				(font
					(size 1.27 1.27)
				)
				(justify right)
			)
		)
		(property "Value" "R_100k_0402"
			(at 270.51 195.58 0)
			(effects
				(font
					(size 1.27 1.27)
					(thickness 0.15)
				)
				(justify left bottom)
				(hide yes)
			)
		)
		(property "Footprint" "antmicro-footprints:R_0402_1005Metric"
			(at 273.05 195.58 0)
			(effects
				(font
					(size 1.27 1.27)
					(thickness 0.15)
				)
				(justify left bottom)
				(hide yes)
			)
		)
		(property "Datasheet" "https://www.bourns.com/docs/product-datasheets/cr.pdf"
			(at 275.59 195.58 0)
			(effects
				(font
					(size 1.27 1.27)
					(thickness 0.15)
				)
				(justify left bottom)
				(hide yes)
			)
		)
		(property "Description" ""
			(at 257.81 215.9 0)
			(effects
				(font
					(size 1.27 1.27)
				)
				(hide yes)
			)
		)
		(property "Manufacturer" "Bourns"
			(at 280.67 195.58 0)
			(effects
				(font
					(size 1.27 1.27)
					(thickness 0.15)
				)
				(justify left bottom)
				(hide yes)
			)
		)
		(property "MPN" "CR0402-FX-1003GLF"
			(at 278.13 195.58 0)
			(effects
				(font
					(size 1.27 1.27)
					(thickness 0.15)
				)
				(justify left bottom)
				(hide yes)
			)
		)
		(property "Val" "100k"
			(at 259.08 214.63 90)
			(effects
				(font
					(size 1.27 1.27)
					(thickness 0.15)
				)
				(justify right)
			)
		)
		(property "License" "Apache-2.0"
			(at 283.21 195.58 0)
			(effects
				(font
					(size 1.27 1.27)
					(thickness 0.15)
				)
				(justify left bottom)
				(hide yes)
			)
		)
		(property "Author" "Antmicro"
			(at 285.75 195.58 0)
			(effects
				(font
					(size 1.27 1.27)
					(thickness 0.15)
				)
				(justify left bottom)
				(hide yes)
			)
		)
		(property "Tolerance" "1%"
			(at 267.97 195.58 0)
			(effects
				(font
					(size 1.27 1.27)
				)
				(justify left bottom)
				(hide yes)
			)
		)
		(pin "1"
		)
		(pin "2"
		)
		(instances
			(project "jetson-orin-baseboard"
				(path ""
					(reference "R185")
					(unit 1)
				)
			)
		)
	)
	(symbol
		(lib_id "antmicroResistors0402:R_1k3_0402")
		(at 113.03 215.9 0)
		(unit 1)
		(exclude_from_sim no)
		(in_bom yes)
		(on_board yes)
		(dnp no)
		(property "Reference" "R123"
			(at 118.11 215.265 0)
			(effects
				(font
					(size 1.27 1.27)
				)
				(justify left bottom)
			)
		)
		(property "Value" "R_1k3_0402"
			(at 133.35 228.6 0)
			(effects
				(font
					(size 1.27 1.27)
					(thickness 0.15)
				)
				(justify left bottom)
				(hide yes)
			)
		)
		(property "Footprint" "antmicro-footprints:R_0402_1005Metric"
			(at 133.35 231.14 0)
			(effects
				(font
					(size 1.27 1.27)
					(thickness 0.15)
				)
				(justify left bottom)
				(hide yes)
			)
		)
		(property "Datasheet" "https://www.bourns.com/docs/product-datasheets/cr.pdf"
			(at 133.35 233.68 0)
			(effects
				(font
					(size 1.27 1.27)
					(thickness 0.15)
				)
				(justify left bottom)
				(hide yes)
			)
		)
		(property "Description" ""
			(at 113.03 215.9 0)
			(effects
				(font
					(size 1.27 1.27)
				)
				(hide yes)
			)
		)
		(property "Manufacturer" "Bourns"
			(at 133.35 238.76 0)
			(effects
				(font
					(size 1.27 1.27)
					(thickness 0.15)
				)
				(justify left bottom)
				(hide yes)
			)
		)
		(property "MPN" "CR0402-FX-1301GLF"
			(at 133.35 236.22 0)
			(effects
				(font
					(size 1.27 1.27)
					(thickness 0.15)
				)
				(justify left bottom)
				(hide yes)
			)
		)
		(property "Val" "1k3"
			(at 109.855 215.265 0)
			(effects
				(font
					(size 1.27 1.27)
					(thickness 0.15)
				)
				(justify left bottom)
			)
		)
		(property "License" "Apache-2.0"
			(at 133.35 241.3 0)
			(effects
				(font
					(size 1.27 1.27)
					(thickness 0.15)
				)
				(justify left bottom)
				(hide yes)
			)
		)
		(property "Author" "Antmicro"
			(at 133.35 243.84 0)
			(effects
				(font
					(size 1.27 1.27)
					(thickness 0.15)
				)
				(justify left bottom)
				(hide yes)
			)
		)
		(property "Tolerance" "1%"
			(at 133.35 226.06 0)
			(effects
				(font
					(size 1.27 1.27)
				)
				(justify left bottom)
				(hide yes)
			)
		)
		(pin "1"
		)
		(pin "2"
		)
		(instances
			(project "jetson-orin-baseboard"
				(path ""
					(reference "R123")
					(unit 1)
				)
			)
		)
	)
	(symbol
		(lib_id "antmicroCapacitorsmisc:C_47u_16V_1206")
		(at 349.25 193.04 90)
		(unit 1)
		(exclude_from_sim no)
		(in_bom yes)
		(on_board yes)
		(dnp no)
		(property "Reference" "C84"
			(at 351.155 187.96 90)
			(effects
				(font
					(size 1.27 1.27)
				)
				(justify right)
			)
		)
		(property "Value" "C_47u_16V_1206"
			(at 359.41 172.72 0)
			(effects
				(font
					(size 1.27 1.27)
					(thickness 0.15)
				)
				(justify left bottom)
				(hide yes)
			)
		)
		(property "Footprint" "antmicro-footprints:C_1206_3216Metric"
			(at 361.95 172.72 0)
			(effects
				(font
					(size 1.27 1.27)
					(thickness 0.15)
				)
				(justify left bottom)
				(hide yes)
			)
		)
		(property "Datasheet" "https://product.tdk.com/en/search/capacitor/ceramic/mlcc/info?part_no=C3216X5R1C476M160AB"
			(at 364.49 172.72 0)
			(effects
				(font
					(size 1.27 1.27)
					(thickness 0.15)
				)
				(justify left bottom)
				(hide yes)
			)
		)
		(property "Description" ""
			(at 349.25 193.04 0)
			(effects
				(font
					(size 1.27 1.27)
				)
				(hide yes)
			)
		)
		(property "Manufacturer" "TDK"
			(at 369.57 172.72 0)
			(effects
				(font
					(size 1.27 1.27)
					(thickness 0.15)
				)
				(justify left bottom)
				(hide yes)
			)
		)
		(property "MPN" "C3216X5R1C476M160AB"
			(at 367.03 172.72 0)
			(effects
				(font
					(size 1.27 1.27)
					(thickness 0.15)
				)
				(justify left bottom)
				(hide yes)
			)
		)
		(property "Val" "47u"
			(at 351.155 190.5 90)
			(effects
				(font
					(size 1.27 1.27)
					(thickness 0.15)
				)
				(justify right)
			)
		)
		(property "License" "Apache-2.0"
			(at 372.11 172.72 0)
			(effects
				(font
					(size 1.27 1.27)
					(thickness 0.15)
				)
				(justify left bottom)
				(hide yes)
			)
		)
		(property "Author" "Antmicro"
			(at 374.65 172.72 0)
			(effects
				(font
					(size 1.27 1.27)
					(thickness 0.15)
				)
				(justify left bottom)
				(hide yes)
			)
		)
		(property "Voltage" "16V"
			(at 351.155 193.04 90)
			(effects
				(font
					(size 1.27 1.27)
				)
				(justify right)
			)
		)
		(property "Dielectric" "X5R"
			(at 379.73 172.72 0)
			(effects
				(font
					(size 1.27 1.27)
				)
				(justify left bottom)
				(hide yes)
			)
		)
		(property "Public" "False"
			(at 382.27 172.72 0)
			(effects
				(font
					(size 1.27 1.27)
				)
				(justify left bottom)
				(hide yes)
			)
		)
		(pin "1"
		)
		(pin "2"
		)
		(instances
			(project "jetson-orin-baseboard"
				(path ""
					(reference "C84")
					(unit 1)
				)
			)
		)
	)
	(symbol
		(lib_id "antmicroResistors0402:R_0R_0402")
		(at 267.97 194.31 180)
		(unit 1)
		(exclude_from_sim no)
		(in_bom no)
		(on_board yes)
		(dnp yes)
		(property "Reference" "R241"
			(at 267.97 193.675 0)
			(effects
				(font
					(size 1.27 1.27)
				)
				(justify right top)
			)
		)
		(property "Value" "R_0R_0402"
			(at 247.65 181.61 0)
			(effects
				(font
					(size 1.27 1.27)
					(thickness 0.15)
				)
				(justify left bottom)
				(hide yes)
			)
		)
		(property "Footprint" "antmicro-footprints:R_0402_1005Metric"
			(at 247.65 179.07 0)
			(effects
				(font
					(size 1.27 1.27)
					(thickness 0.15)
				)
				(justify left bottom)
				(hide yes)
			)
		)
		(property "Datasheet" "https://industrial.panasonic.com/cdbs/www-data/pdf/RDA0000/AOA0000C301.pdf"
			(at 247.65 176.53 0)
			(effects
				(font
					(size 1.27 1.27)
					(thickness 0.15)
				)
				(justify left bottom)
				(hide yes)
			)
		)
		(property "Description" ""
			(at 267.97 194.31 0)
			(effects
				(font
					(size 1.27 1.27)
				)
				(hide yes)
			)
		)
		(property "Manufacturer" "Panasonic"
			(at 247.65 171.45 0)
			(effects
				(font
					(size 1.27 1.27)
					(thickness 0.15)
				)
				(justify left bottom)
				(hide yes)
			)
		)
		(property "MPN" "ERJ2GE0R00X"
			(at 247.65 173.99 0)
			(effects
				(font
					(size 1.27 1.27)
					(thickness 0.15)
				)
				(justify left bottom)
				(hide yes)
			)
		)
		(property "Val" "0R"
			(at 260.35 193.675 0)
			(effects
				(font
					(size 1.27 1.27)
					(thickness 0.15)
				)
				(justify right top)
			)
		)
		(property "License" "Apache-2.0"
			(at 247.65 168.91 0)
			(effects
				(font
					(size 1.27 1.27)
					(thickness 0.15)
				)
				(justify left bottom)
				(hide yes)
			)
		)
		(property "Author" "Antmicro"
			(at 247.65 166.37 0)
			(effects
				(font
					(size 1.27 1.27)
					(thickness 0.15)
				)
				(justify left bottom)
				(hide yes)
			)
		)
		(property "Tolerance" "~"
			(at 247.65 184.15 0)
			(effects
				(font
					(size 1.27 1.27)
				)
				(justify left bottom)
				(hide yes)
			)
		)
		(property "Current" "1A"
			(at 247.65 163.83 0)
			(effects
				(font
					(size 1.27 1.27)
					(thickness 0.15)
				)
				(justify left bottom)
				(hide yes)
			)
		)
		(pin "1"
		)
		(pin "2"
		)
		(instances
			(project "jetson-orin-baseboard"
				(path ""
					(reference "R241")
					(unit 1)
				)
			)
		)
	)
	(symbol
		(lib_id "antmicropower:GNDD")
		(at 220.98 218.44 0)
		(unit 1)
		(exclude_from_sim no)
		(in_bom yes)
		(on_board yes)
		(dnp no)
		(property "Reference" "#PWR0140"
			(at 220.98 224.79 0)
			(effects
				(font
					(size 1.27 1.27)
				)
				(justify left bottom)
				(hide yes)
			)
		)
		(property "Value" "GNDD"
			(at 220.98 221.615 0)
			(effects
				(font
					(size 1.27 1.27)
					(thickness 0.15)
				)
			)
		)
		(property "Footprint" ""
			(at 236.22 228.6 0)
			(effects
				(font
					(size 1.27 1.27)
					(thickness 0.15)
				)
				(justify left bottom)
				(hide yes)
			)
		)
		(property "Datasheet" ""
			(at 236.22 231.14 0)
			(effects
				(font
					(size 1.27 1.27)
					(thickness 0.15)
				)
				(justify left bottom)
				(hide yes)
			)
		)
		(property "Description" ""
			(at 220.98 218.44 0)
			(effects
				(font
					(size 1.27 1.27)
				)
				(hide yes)
			)
		)
		(property "Author" "Antmicro"
			(at 236.22 226.06 0)
			(effects
				(font
					(size 1.27 1.27)
					(thickness 0.15)
				)
				(justify left bottom)
				(hide yes)
			)
		)
		(property "License" "Apache-2.0"
			(at 236.22 228.6 0)
			(effects
				(font
					(size 1.27 1.27)
					(thickness 0.15)
				)
				(justify left bottom)
				(hide yes)
			)
		)
		(pin "1"
		)
		(instances
			(project "jetson-orin-baseboard"
				(path ""
					(reference "#PWR0140")
					(unit 1)
				)
			)
		)
	)
	(symbol
		(lib_id "antmicroDiodesRectifiersSingle:CD-MMBL110S")
		(at 53.34 177.8 0)
		(unit 1)
		(exclude_from_sim no)
		(in_bom yes)
		(on_board yes)
		(dnp no)
		(property "Reference" "D12"
			(at 62.23 172.72 0)
			(effects
				(font
					(size 1.27 1.27)
				)
			)
		)
		(property "Value" "CD-MMBL110S"
			(at 80.01 190.5 0)
			(effects
				(font
					(size 1.27 1.27)
					(thickness 0.15)
				)
				(justify left bottom)
				(hide yes)
			)
		)
		(property "Footprint" "antmicro-footprints:DFN3538"
			(at 80.01 185.42 0)
			(effects
				(font
					(size 1.27 1.27)
					(thickness 0.15)
				)
				(justify left bottom)
				(hide yes)
			)
		)
		(property "Datasheet" "https://www.bourns.com/docs/product-datasheets/CD-MMBL110S.pdf"
			(at 80.01 187.96 0)
			(effects
				(font
					(size 1.27 1.27)
					(thickness 0.15)
				)
				(justify left bottom)
				(hide yes)
			)
		)
		(property "Description" ""
			(at 53.34 177.8 0)
			(effects
				(font
					(size 1.27 1.27)
				)
				(hide yes)
			)
		)
		(property "MPN" "CD-MMBL110S"
			(at 62.23 175.26 0)
			(effects
				(font
					(size 1.27 1.27)
					(thickness 0.15)
				)
			)
		)
		(property "Manufacturer" "Bourns"
			(at 80.01 193.04 0)
			(effects
				(font
					(size 1.27 1.27)
					(thickness 0.15)
				)
				(justify left bottom)
				(hide yes)
			)
		)
		(property "Author" "Antmicro"
			(at 80.01 195.58 0)
			(effects
				(font
					(size 1.27 1.27)
					(thickness 0.15)
				)
				(justify left bottom)
				(hide yes)
			)
		)
		(property "License" "Apache-2.0"
			(at 80.01 198.12 0)
			(effects
				(font
					(size 1.27 1.27)
					(thickness 0.15)
				)
				(justify left bottom)
				(hide yes)
			)
		)
		(pin "1"
		)
		(pin "2"
		)
		(pin "3"
		)
		(pin "4"
		)
		(instances
			(project "jetson-orin-baseboard"
				(path ""
					(reference "D12")
					(unit 1)
				)
			)
		)
	)
	(symbol
		(lib_id "antmicroCapacitorsmisc:C_100n_100V_0805")
		(at 101.6 200.66 90)
		(unit 1)
		(exclude_from_sim no)
		(in_bom yes)
		(on_board yes)
		(dnp no)
		(fields_autoplaced yes)
		(property "Reference" "C76"
			(at 104.14 195.5736 90)
			(effects
				(font
					(size 1.27 1.27)
					(thickness 0.15)
				)
				(justify right)
			)
		)
		(property "Value" "C_100n_100V_0805"
			(at 111.76 180.34 0)
			(effects
				(font
					(size 1.27 1.27)
					(thickness 0.15)
				)
				(justify left bottom)
				(hide yes)
			)
		)
		(property "Footprint" "antmicro-footprints:C_0805_2012Metric"
			(at 114.3 180.34 0)
			(effects
				(font
					(size 1.27 1.27)
					(thickness 0.15)
				)
				(justify left bottom)
				(hide yes)
			)
		)
		(property "Datasheet" "https://product.samsungsem.com/mlcc/CL21B104KCFNNN.do"
			(at 116.84 180.34 0)
			(effects
				(font
					(size 1.27 1.27)
					(thickness 0.15)
				)
				(justify left bottom)
				(hide yes)
			)
		)
		(property "Description" ""
			(at 101.6 200.66 0)
			(effects
				(font
					(size 1.27 1.27)
				)
				(hide yes)
			)
		)
		(property "MPN" "CL21B104KCFNNNE"
			(at 119.38 180.34 0)
			(effects
				(font
					(size 1.27 1.27)
					(thickness 0.15)
				)
				(justify left bottom)
				(hide yes)
			)
		)
		(property "Manufacturer" "Samsung Electro-Mechanics"
			(at 121.92 180.34 0)
			(effects
				(font
					(size 1.27 1.27)
					(thickness 0.15)
				)
				(justify left bottom)
				(hide yes)
			)
		)
		(property "License" "Apache-2.0"
			(at 124.46 180.34 0)
			(effects
				(font
					(size 1.27 1.27)
					(thickness 0.15)
				)
				(justify left bottom)
				(hide yes)
			)
		)
		(property "Author" "Antmicro"
			(at 127 180.34 0)
			(effects
				(font
					(size 1.27 1.27)
					(thickness 0.15)
				)
				(justify left bottom)
				(hide yes)
			)
		)
		(property "Val" "100n"
			(at 104.14 198.1136 90)
			(effects
				(font
					(size 1.27 1.27)
					(thickness 0.15)
				)
				(justify right)
			)
		)
		(property "Voltage" "100V"
			(at 104.14 200.6536 90)
			(effects
				(font
					(size 1.27 1.27)
				)
				(justify right)
			)
		)
		(property "Dielectric" "X7R"
			(at 132.08 180.34 0)
			(effects
				(font
					(size 1.27 1.27)
				)
				(justify left bottom)
				(hide yes)
			)
		)
		(property "Public" "False"
			(at 134.62 180.34 0)
			(effects
				(font
					(size 1.27 1.27)
				)
				(justify left bottom)
				(hide yes)
			)
		)
		(pin "2"
		)
		(pin "1"
		)
		(instances
			(project "jetson-orin-baseboard"
				(path ""
					(reference "C76")
					(unit 1)
				)
			)
		)
	)
	(symbol
		(lib_id "antmicropower:GNDD")
		(at 306.07 217.17 0)
		(unit 1)
		(exclude_from_sim no)
		(in_bom yes)
		(on_board yes)
		(dnp no)
		(property "Reference" "#PWR0146"
			(at 306.07 223.52 0)
			(effects
				(font
					(size 1.27 1.27)
				)
				(justify left bottom)
				(hide yes)
			)
		)
		(property "Value" "GNDD"
			(at 306.07 220.345 0)
			(effects
				(font
					(size 1.27 1.27)
					(thickness 0.15)
				)
			)
		)
		(property "Footprint" ""
			(at 321.31 227.33 0)
			(effects
				(font
					(size 1.27 1.27)
					(thickness 0.15)
				)
				(justify left bottom)
				(hide yes)
			)
		)
		(property "Datasheet" ""
			(at 321.31 229.87 0)
			(effects
				(font
					(size 1.27 1.27)
					(thickness 0.15)
				)
				(justify left bottom)
				(hide yes)
			)
		)
		(property "Description" ""
			(at 306.07 217.17 0)
			(effects
				(font
					(size 1.27 1.27)
				)
				(hide yes)
			)
		)
		(property "Author" "Antmicro"
			(at 321.31 224.79 0)
			(effects
				(font
					(size 1.27 1.27)
					(thickness 0.15)
				)
				(justify left bottom)
				(hide yes)
			)
		)
		(property "License" "Apache-2.0"
			(at 321.31 227.33 0)
			(effects
				(font
					(size 1.27 1.27)
					(thickness 0.15)
				)
				(justify left bottom)
				(hide yes)
			)
		)
		(pin "1"
		)
		(instances
			(project "jetson-orin-baseboard"
				(path ""
					(reference "#PWR0146")
					(unit 1)
				)
			)
		)
	)
	(symbol
		(lib_id "antmicropower:GNDD")
		(at 267.97 237.49 0)
		(unit 1)
		(exclude_from_sim no)
		(in_bom yes)
		(on_board yes)
		(dnp no)
		(property "Reference" "#PWR0145"
			(at 267.97 243.84 0)
			(effects
				(font
					(size 1.27 1.27)
				)
				(justify left bottom)
				(hide yes)
			)
		)
		(property "Value" "GNDD"
			(at 267.97 240.665 0)
			(effects
				(font
					(size 1.27 1.27)
					(thickness 0.15)
				)
			)
		)
		(property "Footprint" ""
			(at 283.21 247.65 0)
			(effects
				(font
					(size 1.27 1.27)
					(thickness 0.15)
				)
				(justify left bottom)
				(hide yes)
			)
		)
		(property "Datasheet" ""
			(at 283.21 250.19 0)
			(effects
				(font
					(size 1.27 1.27)
					(thickness 0.15)
				)
				(justify left bottom)
				(hide yes)
			)
		)
		(property "Description" ""
			(at 267.97 237.49 0)
			(effects
				(font
					(size 1.27 1.27)
				)
				(hide yes)
			)
		)
		(property "Author" "Antmicro"
			(at 283.21 245.11 0)
			(effects
				(font
					(size 1.27 1.27)
					(thickness 0.15)
				)
				(justify left bottom)
				(hide yes)
			)
		)
		(property "License" "Apache-2.0"
			(at 283.21 247.65 0)
			(effects
				(font
					(size 1.27 1.27)
					(thickness 0.15)
				)
				(justify left bottom)
				(hide yes)
			)
		)
		(pin "1"
		)
		(instances
			(project "jetson-orin-baseboard"
				(path ""
					(reference "#PWR0145")
					(unit 1)
				)
			)
		)
	)
	(symbol
		(lib_id "antmicroResistors0402:R_24k9_0402")
		(at 241.3 190.5 90)
		(unit 1)
		(exclude_from_sim no)
		(in_bom yes)
		(on_board yes)
		(dnp no)
		(property "Reference" "R154"
			(at 242.57 186.69 90)
			(effects
				(font
					(size 1.27 1.27)
				)
				(justify right)
			)
		)
		(property "Value" "R_24k9_0402"
			(at 254 170.18 0)
			(effects
				(font
					(size 1.27 1.27)
					(thickness 0.15)
				)
				(justify left bottom)
				(hide yes)
			)
		)
		(property "Footprint" "antmicro-footprints:R_0402_1005Metric"
			(at 256.54 170.18 0)
			(effects
				(font
					(size 1.27 1.27)
					(thickness 0.15)
				)
				(justify left bottom)
				(hide yes)
			)
		)
		(property "Datasheet" "https://www.bourns.com/docs/product-datasheets/cr.pdf"
			(at 259.08 170.18 0)
			(effects
				(font
					(size 1.27 1.27)
					(thickness 0.15)
				)
				(justify left bottom)
				(hide yes)
			)
		)
		(property "Description" ""
			(at 241.3 190.5 0)
			(effects
				(font
					(size 1.27 1.27)
				)
				(hide yes)
			)
		)
		(property "Manufacturer" "Bourns"
			(at 264.16 170.18 0)
			(effects
				(font
					(size 1.27 1.27)
					(thickness 0.15)
				)
				(justify left bottom)
				(hide yes)
			)
		)
		(property "MPN" "CR0402-FX-2492GLF"
			(at 261.62 170.18 0)
			(effects
				(font
					(size 1.27 1.27)
					(thickness 0.15)
				)
				(justify left bottom)
				(hide yes)
			)
		)
		(property "Val" "24k9"
			(at 242.57 189.23 90)
			(effects
				(font
					(size 1.27 1.27)
					(thickness 0.15)
				)
				(justify right)
			)
		)
		(property "License" "Apache-2.0"
			(at 266.7 170.18 0)
			(effects
				(font
					(size 1.27 1.27)
					(thickness 0.15)
				)
				(justify left bottom)
				(hide yes)
			)
		)
		(property "Author" "Antmicro"
			(at 269.24 170.18 0)
			(effects
				(font
					(size 1.27 1.27)
					(thickness 0.15)
				)
				(justify left bottom)
				(hide yes)
			)
		)
		(property "Tolerance" "1%"
			(at 251.46 170.18 0)
			(effects
				(font
					(size 1.27 1.27)
				)
				(justify left bottom)
				(hide yes)
			)
		)
		(pin "1"
		)
		(pin "2"
		)
		(instances
			(project "jetson-orin-baseboard"
				(path ""
					(reference "R154")
					(unit 1)
				)
			)
		)
	)
	(symbol
		(lib_id "antmicropower:GND")
		(at 349.25 199.39 0)
		(unit 1)
		(exclude_from_sim no)
		(in_bom yes)
		(on_board yes)
		(dnp no)
		(property "Reference" "#PWR0327"
			(at 349.25 205.74 0)
			(effects
				(font
					(size 1.27 1.27)
				)
				(justify left bottom)
				(hide yes)
			)
		)
		(property "Value" "GND"
			(at 349.25 203.2 0)
			(effects
				(font
					(size 1.27 1.27)
					(thickness 0.15)
				)
			)
		)
		(property "Footprint" ""
			(at 358.14 207.01 0)
			(effects
				(font
					(size 1.27 1.27)
					(thickness 0.15)
				)
				(justify left bottom)
				(hide yes)
			)
		)
		(property "Datasheet" ""
			(at 358.14 212.09 0)
			(effects
				(font
					(size 1.27 1.27)
					(thickness 0.15)
				)
				(justify left bottom)
				(hide yes)
			)
		)
		(property "Description" ""
			(at 349.25 199.39 0)
			(effects
				(font
					(size 1.27 1.27)
				)
				(hide yes)
			)
		)
		(property "Author" "Antmicro"
			(at 358.14 207.01 0)
			(effects
				(font
					(size 1.27 1.27)
					(thickness 0.15)
				)
				(justify left bottom)
				(hide yes)
			)
		)
		(property "License" "Apache-2.0"
			(at 358.14 209.55 0)
			(effects
				(font
					(size 1.27 1.27)
					(thickness 0.15)
				)
				(justify left bottom)
				(hide yes)
			)
		)
		(pin "1"
		)
		(instances
			(project "jetson-orin-baseboard"
				(path ""
					(reference "#PWR0327")
					(unit 1)
				)
			)
		)
	)
	(symbol
		(lib_id "antmicropower:GND")
		(at 328.93 199.39 0)
		(unit 1)
		(exclude_from_sim no)
		(in_bom yes)
		(on_board yes)
		(dnp no)
		(property "Reference" "#PWR0307"
			(at 328.93 205.74 0)
			(effects
				(font
					(size 1.27 1.27)
				)
				(justify left bottom)
				(hide yes)
			)
		)
		(property "Value" "GND"
			(at 328.93 203.2 0)
			(effects
				(font
					(size 1.27 1.27)
					(thickness 0.15)
				)
			)
		)
		(property "Footprint" ""
			(at 337.82 207.01 0)
			(effects
				(font
					(size 1.27 1.27)
					(thickness 0.15)
				)
				(justify left bottom)
				(hide yes)
			)
		)
		(property "Datasheet" ""
			(at 337.82 212.09 0)
			(effects
				(font
					(size 1.27 1.27)
					(thickness 0.15)
				)
				(justify left bottom)
				(hide yes)
			)
		)
		(property "Description" ""
			(at 328.93 199.39 0)
			(effects
				(font
					(size 1.27 1.27)
				)
				(hide yes)
			)
		)
		(property "Author" "Antmicro"
			(at 337.82 207.01 0)
			(effects
				(font
					(size 1.27 1.27)
					(thickness 0.15)
				)
				(justify left bottom)
				(hide yes)
			)
		)
		(property "License" "Apache-2.0"
			(at 337.82 209.55 0)
			(effects
				(font
					(size 1.27 1.27)
					(thickness 0.15)
				)
				(justify left bottom)
				(hide yes)
			)
		)
		(pin "1"
		)
		(instances
			(project "jetson-orin-baseboard"
				(path ""
					(reference "#PWR0307")
					(unit 1)
				)
			)
		)
	)
	(symbol
		(lib_id "antmicroModularConnectorsJacksWithMagnetics:Bus_RJ45_5-2337992-8")
		(at 185.42 50.8 0)
		(unit 1)
		(exclude_from_sim no)
		(in_bom yes)
		(on_board yes)
		(dnp no)
		(property "Reference" "J6"
			(at 196.215 44.45 0)
			(effects
				(font
					(size 1.27 1.27)
				)
			)
		)
		(property "Value" "Bus_RJ45_5-2337992-8"
			(at 220.98 55.88 0)
			(effects
				(font
					(size 1.27 1.27)
					(thickness 0.15)
				)
				(justify left bottom)
				(hide yes)
			)
		)
		(property "Footprint" "antmicro-footprints:RJ45_X-2337992-8_Horizontal"
			(at 220.98 58.42 0)
			(effects
				(font
					(size 1.27 1.27)
					(thickness 0.15)
				)
				(justify left bottom)
				(hide yes)
			)
		)
		(property "Datasheet" "https://www.te.com/commerce/DocumentDelivery/DDEController?Action=showdoc&DocId=Customer+Drawing%7F5-2337992-8%7FA%7Fpdf%7FEnglish%7FENG_CD_5-2337992-8_A.pdf%7F5-2337992-8"
			(at 220.98 60.96 0)
			(effects
				(font
					(size 1.27 1.27)
					(thickness 0.15)
				)
				(justify left bottom)
				(hide yes)
			)
		)
		(property "Description" ""
			(at 185.42 50.8 0)
			(effects
				(font
					(size 1.27 1.27)
				)
				(hide yes)
			)
		)
		(property "MPN" "5-2337992-8"
			(at 196.215 46.99 0)
			(effects
				(font
					(size 1.27 1.27)
					(thickness 0.15)
				)
			)
		)
		(property "Manufacturer" "TE Connectivity"
			(at 220.98 66.04 0)
			(effects
				(font
					(size 1.27 1.27)
					(thickness 0.15)
				)
				(justify left bottom)
				(hide yes)
			)
		)
		(property "Author" "Antmicro"
			(at 220.98 68.58 0)
			(effects
				(font
					(size 1.27 1.27)
					(thickness 0.15)
				)
				(justify left bottom)
				(hide yes)
			)
		)
		(property "License" "Apache-2.0"
			(at 220.98 71.12 0)
			(effects
				(font
					(size 1.27 1.27)
					(thickness 0.15)
				)
				(justify left bottom)
				(hide yes)
			)
		)
		(pin "1"
		)
		(pin "10"
		)
		(pin "11"
		)
		(pin "12"
		)
		(pin "13"
		)
		(pin "14"
		)
		(pin "15"
		)
		(pin "16"
		)
		(pin "17"
		)
		(pin "18"
		)
		(pin "19"
		)
		(pin "2"
		)
		(pin "20"
		)
		(pin "3"
		)
		(pin "4"
		)
		(pin "5"
		)
		(pin "6"
		)
		(pin "7"
		)
		(pin "8"
		)
		(pin "9"
		)
		(instances
			(project "jetson-orin-baseboard"
				(path ""
					(reference "J6")
					(unit 1)
				)
			)
		)
	)
	(symbol
		(lib_id "antmicroResistors0603:R_0R_0603")
		(at 339.09 196.85 90)
		(unit 1)
		(exclude_from_sim no)
		(in_bom no)
		(on_board yes)
		(dnp yes)
		(property "Reference" "R157"
			(at 340.36 193.04 90)
			(effects
				(font
					(size 1.27 1.27)
				)
				(justify right)
			)
		)
		(property "Value" "R_0R_0603"
			(at 351.79 176.53 0)
			(effects
				(font
					(size 1.27 1.27)
					(thickness 0.15)
				)
				(justify left bottom)
				(hide yes)
			)
		)
		(property "Footprint" "antmicro-footprints:R_0603_1608Metric"
			(at 354.33 176.53 0)
			(effects
				(font
					(size 1.27 1.27)
					(thickness 0.15)
				)
				(justify left bottom)
				(hide yes)
			)
		)
		(property "Datasheet" "https://www.bourns.com/docs/product-datasheets/cr.pdf?sfvrsn=574d41f6_14"
			(at 356.87 176.53 0)
			(effects
				(font
					(size 1.27 1.27)
					(thickness 0.15)
				)
				(justify left bottom)
				(hide yes)
			)
		)
		(property "Description" ""
			(at 339.09 196.85 0)
			(effects
				(font
					(size 1.27 1.27)
				)
				(hide yes)
			)
		)
		(property "Manufacturer" "Bourns"
			(at 361.95 176.53 0)
			(effects
				(font
					(size 1.27 1.27)
					(thickness 0.15)
				)
				(justify left bottom)
				(hide yes)
			)
		)
		(property "MPN" "CR0603-J/-000ELF"
			(at 359.41 176.53 0)
			(effects
				(font
					(size 1.27 1.27)
					(thickness 0.15)
				)
				(justify left bottom)
				(hide yes)
			)
		)
		(property "Val" "0R"
			(at 340.36 195.58 90)
			(effects
				(font
					(size 1.27 1.27)
					(thickness 0.15)
				)
				(justify right)
			)
		)
		(property "License" "Apache-2.0"
			(at 364.49 176.53 0)
			(effects
				(font
					(size 1.27 1.27)
					(thickness 0.15)
				)
				(justify left bottom)
				(hide yes)
			)
		)
		(property "Author" "Antmicro"
			(at 367.03 176.53 0)
			(effects
				(font
					(size 1.27 1.27)
					(thickness 0.15)
				)
				(justify left bottom)
				(hide yes)
			)
		)
		(property "Tolerance" "~"
			(at 349.25 176.53 0)
			(effects
				(font
					(size 1.27 1.27)
				)
				(justify left bottom)
				(hide yes)
			)
		)
		(property "Current" "1A"
			(at 369.57 176.53 0)
			(effects
				(font
					(size 1.27 1.27)
					(thickness 0.15)
				)
				(justify left bottom)
				(hide yes)
			)
		)
		(pin "1"
		)
		(pin "2"
		)
		(instances
			(project "jetson-orin-baseboard"
				(path ""
					(reference "R157")
					(unit 1)
				)
			)
		)
	)
	(symbol
		(lib_id "antmicropower:GNDD")
		(at 297.18 217.17 0)
		(unit 1)
		(exclude_from_sim no)
		(in_bom yes)
		(on_board yes)
		(dnp no)
		(property "Reference" "#PWR0306"
			(at 297.18 223.52 0)
			(effects
				(font
					(size 1.27 1.27)
				)
				(justify left bottom)
				(hide yes)
			)
		)
		(property "Value" "GNDD"
			(at 297.18 220.345 0)
			(effects
				(font
					(size 1.27 1.27)
					(thickness 0.15)
				)
			)
		)
		(property "Footprint" ""
			(at 312.42 227.33 0)
			(effects
				(font
					(size 1.27 1.27)
					(thickness 0.15)
				)
				(justify left bottom)
				(hide yes)
			)
		)
		(property "Datasheet" ""
			(at 312.42 229.87 0)
			(effects
				(font
					(size 1.27 1.27)
					(thickness 0.15)
				)
				(justify left bottom)
				(hide yes)
			)
		)
		(property "Description" ""
			(at 297.18 217.17 0)
			(effects
				(font
					(size 1.27 1.27)
				)
				(hide yes)
			)
		)
		(property "Author" "Antmicro"
			(at 312.42 224.79 0)
			(effects
				(font
					(size 1.27 1.27)
					(thickness 0.15)
				)
				(justify left bottom)
				(hide yes)
			)
		)
		(property "License" "Apache-2.0"
			(at 312.42 227.33 0)
			(effects
				(font
					(size 1.27 1.27)
					(thickness 0.15)
				)
				(justify left bottom)
				(hide yes)
			)
		)
		(pin "1"
		)
		(instances
			(project "jetson-orin-baseboard"
				(path ""
					(reference "#PWR0306")
					(unit 1)
				)
			)
		)
	)
	(symbol
		(lib_id "antmicroResistors0402:R_24k9_0402")
		(at 133.35 189.23 90)
		(unit 1)
		(exclude_from_sim no)
		(in_bom yes)
		(on_board yes)
		(dnp no)
		(property "Reference" "R146"
			(at 132.08 185.42 90)
			(effects
				(font
					(size 1.27 1.27)
				)
				(justify left)
			)
		)
		(property "Value" "R_24k9_0402"
			(at 146.05 168.91 0)
			(effects
				(font
					(size 1.27 1.27)
					(thickness 0.15)
				)
				(justify left bottom)
				(hide yes)
			)
		)
		(property "Footprint" "antmicro-footprints:R_0402_1005Metric"
			(at 148.59 168.91 0)
			(effects
				(font
					(size 1.27 1.27)
					(thickness 0.15)
				)
				(justify left bottom)
				(hide yes)
			)
		)
		(property "Datasheet" "https://www.bourns.com/docs/product-datasheets/cr.pdf"
			(at 151.13 168.91 0)
			(effects
				(font
					(size 1.27 1.27)
					(thickness 0.15)
				)
				(justify left bottom)
				(hide yes)
			)
		)
		(property "Description" ""
			(at 133.35 189.23 0)
			(effects
				(font
					(size 1.27 1.27)
				)
				(hide yes)
			)
		)
		(property "Manufacturer" "Bourns"
			(at 156.21 168.91 0)
			(effects
				(font
					(size 1.27 1.27)
					(thickness 0.15)
				)
				(justify left bottom)
				(hide yes)
			)
		)
		(property "MPN" "CR0402-FX-2492GLF"
			(at 153.67 168.91 0)
			(effects
				(font
					(size 1.27 1.27)
					(thickness 0.15)
				)
				(justify left bottom)
				(hide yes)
			)
		)
		(property "Val" "24k9"
			(at 132.08 187.96 90)
			(effects
				(font
					(size 1.27 1.27)
					(thickness 0.15)
				)
				(justify left)
			)
		)
		(property "License" "Apache-2.0"
			(at 158.75 168.91 0)
			(effects
				(font
					(size 1.27 1.27)
					(thickness 0.15)
				)
				(justify left bottom)
				(hide yes)
			)
		)
		(property "Author" "Antmicro"
			(at 161.29 168.91 0)
			(effects
				(font
					(size 1.27 1.27)
					(thickness 0.15)
				)
				(justify left bottom)
				(hide yes)
			)
		)
		(property "Tolerance" "1%"
			(at 143.51 168.91 0)
			(effects
				(font
					(size 1.27 1.27)
				)
				(justify left bottom)
				(hide yes)
			)
		)
		(pin "1"
		)
		(pin "2"
		)
		(instances
			(project "jetson-orin-baseboard"
				(path ""
					(reference "R146")
					(unit 1)
				)
			)
		)
	)
	(symbol
		(lib_id "antmicroResistors0402:R_49k9_0402")
		(at 113.03 218.44 0)
		(unit 1)
		(exclude_from_sim no)
		(in_bom yes)
		(on_board yes)
		(dnp no)
		(property "Reference" "R142"
			(at 118.11 217.805 0)
			(effects
				(font
					(size 1.27 1.27)
				)
				(justify left bottom)
			)
		)
		(property "Value" "R_49k9_0402"
			(at 133.35 231.14 0)
			(effects
				(font
					(size 1.27 1.27)
					(thickness 0.15)
				)
				(justify left bottom)
				(hide yes)
			)
		)
		(property "Footprint" "antmicro-footprints:R_0402_1005Metric"
			(at 133.35 233.68 0)
			(effects
				(font
					(size 1.27 1.27)
					(thickness 0.15)
				)
				(justify left bottom)
				(hide yes)
			)
		)
		(property "Datasheet" "https://www.bourns.com/docs/product-datasheets/cr.pdf"
			(at 133.35 236.22 0)
			(effects
				(font
					(size 1.27 1.27)
					(thickness 0.15)
				)
				(justify left bottom)
				(hide yes)
			)
		)
		(property "Description" ""
			(at 113.03 218.44 0)
			(effects
				(font
					(size 1.27 1.27)
				)
				(hide yes)
			)
		)
		(property "Manufacturer" "Bourns"
			(at 133.35 241.3 0)
			(effects
				(font
					(size 1.27 1.27)
					(thickness 0.15)
				)
				(justify left bottom)
				(hide yes)
			)
		)
		(property "MPN" "CR0402-FX-4992GLF"
			(at 133.35 238.76 0)
			(effects
				(font
					(size 1.27 1.27)
					(thickness 0.15)
				)
				(justify left bottom)
				(hide yes)
			)
		)
		(property "Val" "49k9"
			(at 108.585 217.805 0)
			(effects
				(font
					(size 1.27 1.27)
					(thickness 0.15)
				)
				(justify left bottom)
			)
		)
		(property "License" "Apache-2.0"
			(at 133.35 243.84 0)
			(effects
				(font
					(size 1.27 1.27)
					(thickness 0.15)
				)
				(justify left bottom)
				(hide yes)
			)
		)
		(property "Author" "Antmicro"
			(at 133.35 246.38 0)
			(effects
				(font
					(size 1.27 1.27)
					(thickness 0.15)
				)
				(justify left bottom)
				(hide yes)
			)
		)
		(property "Tolerance" "1%"
			(at 133.35 228.6 0)
			(effects
				(font
					(size 1.27 1.27)
				)
				(justify left bottom)
				(hide yes)
			)
		)
		(pin "1"
		)
		(pin "2"
		)
		(instances
			(project "jetson-orin-baseboard"
				(path ""
					(reference "R142")
					(unit 1)
				)
			)
		)
	)
	(symbol
		(lib_id "antmicroResistors0603:R_0R_0603")
		(at 339.09 184.15 270)
		(unit 1)
		(exclude_from_sim no)
		(in_bom no)
		(on_board yes)
		(dnp yes)
		(property "Reference" "R243"
			(at 340.36 185.42 90)
			(effects
				(font
					(size 1.27 1.27)
				)
				(justify left)
			)
		)
		(property "Value" "R_0R_0603"
			(at 326.39 204.47 0)
			(effects
				(font
					(size 1.27 1.27)
					(thickness 0.15)
				)
				(justify left bottom)
				(hide yes)
			)
		)
		(property "Footprint" "antmicro-footprints:R_0603_1608Metric"
			(at 323.85 204.47 0)
			(effects
				(font
					(size 1.27 1.27)
					(thickness 0.15)
				)
				(justify left bottom)
				(hide yes)
			)
		)
		(property "Datasheet" "https://www.bourns.com/docs/product-datasheets/cr.pdf?sfvrsn=574d41f6_14"
			(at 321.31 204.47 0)
			(effects
				(font
					(size 1.27 1.27)
					(thickness 0.15)
				)
				(justify left bottom)
				(hide yes)
			)
		)
		(property "Description" ""
			(at 339.09 184.15 0)
			(effects
				(font
					(size 1.27 1.27)
				)
				(hide yes)
			)
		)
		(property "Manufacturer" "Bourns"
			(at 316.23 204.47 0)
			(effects
				(font
					(size 1.27 1.27)
					(thickness 0.15)
				)
				(justify left bottom)
				(hide yes)
			)
		)
		(property "MPN" "CR0603-J/-000ELF"
			(at 318.77 204.47 0)
			(effects
				(font
					(size 1.27 1.27)
					(thickness 0.15)
				)
				(justify left bottom)
				(hide yes)
			)
		)
		(property "Val" "0R"
			(at 340.36 187.96 90)
			(effects
				(font
					(size 1.27 1.27)
					(thickness 0.15)
				)
				(justify left)
			)
		)
		(property "License" "Apache-2.0"
			(at 313.69 204.47 0)
			(effects
				(font
					(size 1.27 1.27)
					(thickness 0.15)
				)
				(justify left bottom)
				(hide yes)
			)
		)
		(property "Author" "Antmicro"
			(at 311.15 204.47 0)
			(effects
				(font
					(size 1.27 1.27)
					(thickness 0.15)
				)
				(justify left bottom)
				(hide yes)
			)
		)
		(property "Tolerance" "~"
			(at 328.93 204.47 0)
			(effects
				(font
					(size 1.27 1.27)
				)
				(justify left bottom)
				(hide yes)
			)
		)
		(property "Current" "1A"
			(at 308.61 204.47 0)
			(effects
				(font
					(size 1.27 1.27)
					(thickness 0.15)
				)
				(justify left bottom)
				(hide yes)
			)
		)
		(pin "1"
		)
		(pin "2"
		)
		(instances
			(project "jetson-orin-baseboard"
				(path ""
					(reference "R243")
					(unit 1)
				)
			)
		)
	)
	(symbol
		(lib_id "antmicroCapacitors0603:C_10n_0603")
		(at 179.07 92.71 90)
		(unit 1)
		(exclude_from_sim no)
		(in_bom yes)
		(on_board yes)
		(dnp no)
		(fields_autoplaced yes)
		(property "Reference" "C77"
			(at 181.61 88.8936 90)
			(effects
				(font
					(size 1.27 1.27)
					(thickness 0.15)
				)
				(justify right)
			)
		)
		(property "Value" "C_10n_0603"
			(at 189.23 72.39 0)
			(effects
				(font
					(size 1.27 1.27)
					(thickness 0.15)
				)
				(justify left bottom)
				(hide yes)
			)
		)
		(property "Footprint" "antmicro-footprints:C_0603_1608Metric"
			(at 191.77 72.39 0)
			(effects
				(font
					(size 1.27 1.27)
					(thickness 0.15)
				)
				(justify left bottom)
				(hide yes)
			)
		)
		(property "Datasheet" "https://spicat.kyocera-avx.com/product/mlcc/chartview/06031C103JAT2A/"
			(at 194.31 72.39 0)
			(effects
				(font
					(size 1.27 1.27)
					(thickness 0.15)
				)
				(justify left bottom)
				(hide yes)
			)
		)
		(property "Description" ""
			(at 179.07 92.71 0)
			(effects
				(font
					(size 1.27 1.27)
				)
				(hide yes)
			)
		)
		(property "MPN" "06031C103JAT2A"
			(at 196.85 72.39 0)
			(effects
				(font
					(size 1.27 1.27)
					(thickness 0.15)
				)
				(justify left bottom)
				(hide yes)
			)
		)
		(property "Manufacturer" "AVX"
			(at 199.39 72.39 0)
			(effects
				(font
					(size 1.27 1.27)
					(thickness 0.15)
				)
				(justify left bottom)
				(hide yes)
			)
		)
		(property "License" "Apache-2.0"
			(at 201.93 72.39 0)
			(effects
				(font
					(size 1.27 1.27)
					(thickness 0.15)
				)
				(justify left bottom)
				(hide yes)
			)
		)
		(property "Author" "Antmicro"
			(at 204.47 72.39 0)
			(effects
				(font
					(size 1.27 1.27)
					(thickness 0.15)
				)
				(justify left bottom)
				(hide yes)
			)
		)
		(property "Val" "10n"
			(at 181.61 91.4336 90)
			(effects
				(font
					(size 1.27 1.27)
					(thickness 0.15)
				)
				(justify right)
			)
		)
		(property "Voltage" ""
			(at 207.01 72.39 0)
			(effects
				(font
					(size 1.27 1.27)
				)
				(justify left bottom)
				(hide yes)
			)
		)
		(property "Dielectric" ""
			(at 209.55 72.39 0)
			(effects
				(font
					(size 1.27 1.27)
				)
				(justify left bottom)
				(hide yes)
			)
		)
		(pin "2"
		)
		(pin "1"
		)
		(instances
			(project "jetson-orin-baseboard"
				(path ""
					(reference "C77")
					(unit 1)
				)
			)
		)
	)
	(symbol
		(lib_id "antmicropower:GND")
		(at 210.82 93.98 0)
		(unit 1)
		(exclude_from_sim no)
		(in_bom yes)
		(on_board yes)
		(dnp no)
		(property "Reference" "#PWR0135"
			(at 210.82 100.33 0)
			(effects
				(font
					(size 1.27 1.27)
				)
				(justify left bottom)
				(hide yes)
			)
		)
		(property "Value" "GND"
			(at 210.82 97.79 0)
			(effects
				(font
					(size 1.27 1.27)
					(thickness 0.15)
				)
			)
		)
		(property "Footprint" ""
			(at 219.71 101.6 0)
			(effects
				(font
					(size 1.27 1.27)
					(thickness 0.15)
				)
				(justify left bottom)
				(hide yes)
			)
		)
		(property "Datasheet" ""
			(at 219.71 106.68 0)
			(effects
				(font
					(size 1.27 1.27)
					(thickness 0.15)
				)
				(justify left bottom)
				(hide yes)
			)
		)
		(property "Description" ""
			(at 210.82 93.98 0)
			(effects
				(font
					(size 1.27 1.27)
				)
				(hide yes)
			)
		)
		(property "Author" "Antmicro"
			(at 219.71 101.6 0)
			(effects
				(font
					(size 1.27 1.27)
					(thickness 0.15)
				)
				(justify left bottom)
				(hide yes)
			)
		)
		(property "License" "Apache-2.0"
			(at 219.71 104.14 0)
			(effects
				(font
					(size 1.27 1.27)
					(thickness 0.15)
				)
				(justify left bottom)
				(hide yes)
			)
		)
		(pin "1"
		)
		(instances
			(project "jetson-orin-baseboard"
				(path ""
					(reference "#PWR0135")
					(unit 1)
				)
			)
		)
	)
	(symbol
		(lib_id "antmicroResistors0402:R_10k_0402")
		(at 187.96 189.23 90)
		(unit 1)
		(exclude_from_sim no)
		(in_bom no)
		(on_board yes)
		(dnp yes)
		(property "Reference" "R153"
			(at 189.23 185.42 90)
			(effects
				(font
					(size 1.27 1.27)
				)
				(justify right)
			)
		)
		(property "Value" "R_10k_0402"
			(at 200.66 168.91 0)
			(effects
				(font
					(size 1.27 1.27)
					(thickness 0.15)
				)
				(justify left bottom)
				(hide yes)
			)
		)
		(property "Footprint" "antmicro-footprints:R_0402_1005Metric"
			(at 203.2 168.91 0)
			(effects
				(font
					(size 1.27 1.27)
					(thickness 0.15)
				)
				(justify left bottom)
				(hide yes)
			)
		)
		(property "Datasheet" "https://www.bourns.com/docs/product-datasheets/cr.pdf"
			(at 205.74 168.91 0)
			(effects
				(font
					(size 1.27 1.27)
					(thickness 0.15)
				)
				(justify left bottom)
				(hide yes)
			)
		)
		(property "Description" ""
			(at 187.96 189.23 0)
			(effects
				(font
					(size 1.27 1.27)
				)
				(hide yes)
			)
		)
		(property "Manufacturer" "Bourns"
			(at 210.82 168.91 0)
			(effects
				(font
					(size 1.27 1.27)
					(thickness 0.15)
				)
				(justify left bottom)
				(hide yes)
			)
		)
		(property "MPN" "CR0402-FX-1002GLF"
			(at 208.28 168.91 0)
			(effects
				(font
					(size 1.27 1.27)
					(thickness 0.15)
				)
				(justify left bottom)
				(hide yes)
			)
		)
		(property "Val" "10k"
			(at 189.23 187.96 90)
			(effects
				(font
					(size 1.27 1.27)
					(thickness 0.15)
				)
				(justify right)
			)
		)
		(property "License" "Apache-2.0"
			(at 213.36 168.91 0)
			(effects
				(font
					(size 1.27 1.27)
					(thickness 0.15)
				)
				(justify left bottom)
				(hide yes)
			)
		)
		(property "Author" "Antmicro"
			(at 215.9 168.91 0)
			(effects
				(font
					(size 1.27 1.27)
					(thickness 0.15)
				)
				(justify left bottom)
				(hide yes)
			)
		)
		(property "Tolerance" "1%"
			(at 198.12 168.91 0)
			(effects
				(font
					(size 1.27 1.27)
				)
				(justify left bottom)
				(hide yes)
			)
		)
		(pin "1"
		)
		(pin "2"
		)
		(instances
			(project "jetson-orin-baseboard"
				(path ""
					(reference "R153")
					(unit 1)
				)
			)
		)
	)
	(symbol
		(lib_id "antmicroTransistorsFETsMOSFETsSingle:PJE138K")
		(at 267.97 207.01 0)
		(unit 1)
		(exclude_from_sim no)
		(in_bom yes)
		(on_board yes)
		(dnp no)
		(property "Reference" "Q17"
			(at 276.86 203.2 0)
			(effects
				(font
					(size 1.27 1.27)
					(thickness 0.15)
				)
				(justify left)
			)
		)
		(property "Value" "PJE138K"
			(at 290.83 215.9 0)
			(effects
				(font
					(size 1.27 1.27)
					(thickness 0.15)
				)
				(justify left bottom)
				(hide yes)
			)
		)
		(property "Footprint" "antmicro-footprints:SOT-523"
			(at 290.83 218.44 0)
			(effects
				(font
					(size 1.27 1.27)
					(thickness 0.15)
				)
				(justify left bottom)
				(hide yes)
			)
		)
		(property "Datasheet" "https://www.mouser.com/datasheet/2/1057/PJE138K-1876698.pdf"
			(at 290.83 220.98 0)
			(effects
				(font
					(size 1.27 1.27)
					(thickness 0.15)
				)
				(justify left bottom)
				(hide yes)
			)
		)
		(property "Description" ""
			(at 267.97 207.01 0)
			(effects
				(font
					(size 1.27 1.27)
				)
				(hide yes)
			)
		)
		(property "MPN" "PJE138K_R1_00001"
			(at 276.86 205.74 0)
			(effects
				(font
					(size 1.27 1.27)
					(thickness 0.15)
				)
				(justify left)
			)
		)
		(property "Manufacturer" "PANJIT"
			(at 290.83 226.06 0)
			(effects
				(font
					(size 1.27 1.27)
					(thickness 0.15)
				)
				(justify left bottom)
				(hide yes)
			)
		)
		(property "Author" "Antmicro"
			(at 290.83 228.6 0)
			(effects
				(font
					(size 1.27 1.27)
					(thickness 0.15)
				)
				(justify left bottom)
				(hide yes)
			)
		)
		(property "License" "Apache-2.0"
			(at 290.83 231.14 0)
			(effects
				(font
					(size 1.27 1.27)
					(thickness 0.15)
				)
				(justify left bottom)
				(hide yes)
			)
		)
		(pin "2"
		)
		(pin "3"
		)
		(pin "1"
		)
		(instances
			(project "jetson-orin-baseboard"
				(path ""
					(reference "Q17")
					(unit 1)
				)
			)
		)
	)
	(symbol
		(lib_id "antmicroCapacitorsmisc:C_22u_100V_2220")
		(at 231.14 204.47 90)
		(unit 1)
		(exclude_from_sim no)
		(in_bom yes)
		(on_board yes)
		(dnp no)
		(property "Reference" "C82"
			(at 233.045 199.39 90)
			(effects
				(font
					(size 1.27 1.27)
				)
				(justify right)
			)
		)
		(property "Value" "C_22u_100V_2220"
			(at 241.3 184.15 0)
			(effects
				(font
					(size 1.27 1.27)
					(thickness 0.15)
				)
				(justify left bottom)
				(hide yes)
			)
		)
		(property "Footprint" "antmicro-footprints:C_2220_5650Metric"
			(at 243.84 184.15 0)
			(effects
				(font
					(size 1.27 1.27)
					(thickness 0.15)
				)
				(justify left bottom)
				(hide yes)
			)
		)
		(property "Datasheet" "https://product.tdk.com/en/search/capacitor/ceramic/mlcc/info?part_no=C5750X7S2A226M280KB"
			(at 246.38 184.15 0)
			(effects
				(font
					(size 1.27 1.27)
					(thickness 0.15)
				)
				(justify left bottom)
				(hide yes)
			)
		)
		(property "Description" ""
			(at 231.14 204.47 0)
			(effects
				(font
					(size 1.27 1.27)
				)
				(hide yes)
			)
		)
		(property "Manufacturer" "TDK"
			(at 251.46 184.15 0)
			(effects
				(font
					(size 1.27 1.27)
					(thickness 0.15)
				)
				(justify left bottom)
				(hide yes)
			)
		)
		(property "MPN" "C5750X7S2A226M280KB"
			(at 248.92 184.15 0)
			(effects
				(font
					(size 1.27 1.27)
					(thickness 0.15)
				)
				(justify left bottom)
				(hide yes)
			)
		)
		(property "Val" "22u"
			(at 233.045 201.93 90)
			(effects
				(font
					(size 1.27 1.27)
					(thickness 0.15)
				)
				(justify right)
			)
		)
		(property "License" "Apache-2.0"
			(at 254 184.15 0)
			(effects
				(font
					(size 1.27 1.27)
					(thickness 0.15)
				)
				(justify left bottom)
				(hide yes)
			)
		)
		(property "Author" "Antmicro"
			(at 256.54 184.15 0)
			(effects
				(font
					(size 1.27 1.27)
					(thickness 0.15)
				)
				(justify left bottom)
				(hide yes)
			)
		)
		(property "Voltage" "100V"
			(at 233.045 204.47 90)
			(effects
				(font
					(size 1.27 1.27)
				)
				(justify right)
			)
		)
		(property "Dielectric" "X7S"
			(at 261.62 184.15 0)
			(effects
				(font
					(size 1.27 1.27)
				)
				(justify left bottom)
				(hide yes)
			)
		)
		(property "Public" "False"
			(at 264.16 184.15 0)
			(effects
				(font
					(size 1.27 1.27)
				)
				(justify left bottom)
				(hide yes)
			)
		)
		(pin "1"
		)
		(pin "2"
		)
		(instances
			(project "jetson-orin-baseboard"
				(path ""
					(reference "C82")
					(unit 1)
				)
			)
		)
	)
	(symbol
		(lib_id "antmicropower:GNDD")
		(at 257.81 218.44 0)
		(unit 1)
		(exclude_from_sim no)
		(in_bom yes)
		(on_board yes)
		(dnp no)
		(property "Reference" "#PWR0291"
			(at 257.81 224.79 0)
			(effects
				(font
					(size 1.27 1.27)
				)
				(justify left bottom)
				(hide yes)
			)
		)
		(property "Value" "GNDD"
			(at 257.81 221.615 0)
			(effects
				(font
					(size 1.27 1.27)
					(thickness 0.15)
				)
			)
		)
		(property "Footprint" ""
			(at 273.05 228.6 0)
			(effects
				(font
					(size 1.27 1.27)
					(thickness 0.15)
				)
				(justify left bottom)
				(hide yes)
			)
		)
		(property "Datasheet" ""
			(at 273.05 231.14 0)
			(effects
				(font
					(size 1.27 1.27)
					(thickness 0.15)
				)
				(justify left bottom)
				(hide yes)
			)
		)
		(property "Description" ""
			(at 257.81 218.44 0)
			(effects
				(font
					(size 1.27 1.27)
				)
				(hide yes)
			)
		)
		(property "Author" "Antmicro"
			(at 273.05 226.06 0)
			(effects
				(font
					(size 1.27 1.27)
					(thickness 0.15)
				)
				(justify left bottom)
				(hide yes)
			)
		)
		(property "License" "Apache-2.0"
			(at 273.05 228.6 0)
			(effects
				(font
					(size 1.27 1.27)
					(thickness 0.15)
				)
				(justify left bottom)
				(hide yes)
			)
		)
		(pin "1"
		)
		(instances
			(project "jetson-orin-baseboard"
				(path ""
					(reference "#PWR0291")
					(unit 1)
				)
			)
		)
	)
	(symbol
		(lib_id "antmicropower:GND")
		(at 359.41 199.39 0)
		(unit 1)
		(exclude_from_sim no)
		(in_bom yes)
		(on_board yes)
		(dnp no)
		(property "Reference" "#PWR0328"
			(at 359.41 205.74 0)
			(effects
				(font
					(size 1.27 1.27)
				)
				(justify left bottom)
				(hide yes)
			)
		)
		(property "Value" "GND"
			(at 359.41 203.2 0)
			(effects
				(font
					(size 1.27 1.27)
					(thickness 0.15)
				)
			)
		)
		(property "Footprint" ""
			(at 368.3 207.01 0)
			(effects
				(font
					(size 1.27 1.27)
					(thickness 0.15)
				)
				(justify left bottom)
				(hide yes)
			)
		)
		(property "Datasheet" ""
			(at 368.3 212.09 0)
			(effects
				(font
					(size 1.27 1.27)
					(thickness 0.15)
				)
				(justify left bottom)
				(hide yes)
			)
		)
		(property "Description" ""
			(at 359.41 199.39 0)
			(effects
				(font
					(size 1.27 1.27)
				)
				(hide yes)
			)
		)
		(property "Author" "Antmicro"
			(at 368.3 207.01 0)
			(effects
				(font
					(size 1.27 1.27)
					(thickness 0.15)
				)
				(justify left bottom)
				(hide yes)
			)
		)
		(property "License" "Apache-2.0"
			(at 368.3 209.55 0)
			(effects
				(font
					(size 1.27 1.27)
					(thickness 0.15)
				)
				(justify left bottom)
				(hide yes)
			)
		)
		(pin "1"
		)
		(instances
			(project "jetson-orin-baseboard"
				(path ""
					(reference "#PWR0328")
					(unit 1)
				)
			)
		)
	)
	(symbol
		(lib_id "antmicropower:PWR_FLAG")
		(at 101.6 180.34 0)
		(unit 1)
		(exclude_from_sim no)
		(in_bom yes)
		(on_board yes)
		(dnp no)
		(property "Reference" "#FLG09"
			(at 101.6 178.435 0)
			(effects
				(font
					(size 1.27 1.27)
				)
				(hide yes)
			)
		)
		(property "Value" "PWR_FLAG"
			(at 101.6 176.53 0)
			(effects
				(font
					(size 1.27 1.27)
				)
			)
		)
		(property "Footprint" ""
			(at 101.6 180.34 0)
			(effects
				(font
					(size 1.27 1.27)
				)
				(hide yes)
			)
		)
		(property "Datasheet" ""
			(at 101.6 180.34 0)
			(effects
				(font
					(size 1.27 1.27)
				)
				(hide yes)
			)
		)
		(property "Description" ""
			(at 101.6 180.34 0)
			(effects
				(font
					(size 1.27 1.27)
				)
				(hide yes)
			)
		)
		(pin "1"
		)
		(instances
			(project "jetson-orin-baseboard"
				(path ""
					(reference "#FLG09")
					(unit 1)
				)
			)
		)
	)
	(symbol
		(lib_id "antmicropower:PWR_FLAG")
		(at 96.52 215.9 180)
		(unit 1)
		(exclude_from_sim no)
		(in_bom yes)
		(on_board yes)
		(dnp no)
		(property "Reference" "#FLG010"
			(at 96.52 217.805 0)
			(effects
				(font
					(size 1.27 1.27)
				)
				(hide yes)
			)
		)
		(property "Value" "PWR_FLAG"
			(at 96.52 219.71 0)
			(effects
				(font
					(size 1.27 1.27)
				)
			)
		)
		(property "Footprint" ""
			(at 96.52 215.9 0)
			(effects
				(font
					(size 1.27 1.27)
				)
				(hide yes)
			)
		)
		(property "Datasheet" ""
			(at 96.52 215.9 0)
			(effects
				(font
					(size 1.27 1.27)
				)
				(hide yes)
			)
		)
		(property "Description" ""
			(at 96.52 215.9 0)
			(effects
				(font
					(size 1.27 1.27)
				)
				(hide yes)
			)
		)
		(pin "1"
		)
		(instances
			(project "jetson-orin-baseboard"
				(path ""
					(reference "#FLG010")
					(unit 1)
				)
			)
		)
	)
	(symbol
		(lib_id "antmicroResistors0402:R_1k2_0402")
		(at 127 209.55 90)
		(unit 1)
		(exclude_from_sim no)
		(in_bom yes)
		(on_board yes)
		(dnp no)
		(property "Reference" "R145"
			(at 128.27 205.74 90)
			(effects
				(font
					(size 1.27 1.27)
				)
				(justify right)
			)
		)
		(property "Value" "R_1k2_0402"
			(at 139.7 189.23 0)
			(effects
				(font
					(size 1.27 1.27)
					(thickness 0.15)
				)
				(justify left bottom)
				(hide yes)
			)
		)
		(property "Footprint" "antmicro-footprints:R_0402_1005Metric"
			(at 142.24 189.23 0)
			(effects
				(font
					(size 1.27 1.27)
					(thickness 0.15)
				)
				(justify left bottom)
				(hide yes)
			)
		)
		(property "Datasheet" "https://www.bourns.com/docs/product-datasheets/cr.pdf"
			(at 144.78 189.23 0)
			(effects
				(font
					(size 1.27 1.27)
					(thickness 0.15)
				)
				(justify left bottom)
				(hide yes)
			)
		)
		(property "Description" ""
			(at 127 209.55 0)
			(effects
				(font
					(size 1.27 1.27)
				)
				(hide yes)
			)
		)
		(property "Manufacturer" "Bourns"
			(at 149.86 189.23 0)
			(effects
				(font
					(size 1.27 1.27)
					(thickness 0.15)
				)
				(justify left bottom)
				(hide yes)
			)
		)
		(property "MPN" "CR0402-FX-1201GLF"
			(at 147.32 189.23 0)
			(effects
				(font
					(size 1.27 1.27)
					(thickness 0.15)
				)
				(justify left bottom)
				(hide yes)
			)
		)
		(property "Val" "1k2"
			(at 128.27 208.28 90)
			(effects
				(font
					(size 1.27 1.27)
					(thickness 0.15)
				)
				(justify right)
			)
		)
		(property "License" "Apache-2.0"
			(at 152.4 189.23 0)
			(effects
				(font
					(size 1.27 1.27)
					(thickness 0.15)
				)
				(justify left bottom)
				(hide yes)
			)
		)
		(property "Author" "Antmicro"
			(at 154.94 189.23 0)
			(effects
				(font
					(size 1.27 1.27)
					(thickness 0.15)
				)
				(justify left bottom)
				(hide yes)
			)
		)
		(property "Tolerance" "1%"
			(at 137.16 189.23 0)
			(effects
				(font
					(size 1.27 1.27)
				)
				(justify left bottom)
				(hide yes)
			)
		)
		(pin "1"
		)
		(pin "2"
		)
		(instances
			(project "jetson-orin-baseboard"
				(path ""
					(reference "R145")
					(unit 1)
				)
			)
		)
	)
	(symbol
		(lib_id "antmicroTVSDiodes:PTVS58VS1UR,115")
		(at 96.52 195.58 270)
		(unit 1)
		(exclude_from_sim no)
		(in_bom yes)
		(on_board yes)
		(dnp no)
		(fields_autoplaced yes)
		(property "Reference" "D14"
			(at 93.98 196.85 90)
			(effects
				(font
					(size 1.27 1.27)
				)
				(justify right)
			)
		)
		(property "Value" "PTVS58VS1UR,115"
			(at 81.28 217.17 0)
			(effects
				(font
					(size 1.27 1.27)
					(thickness 0.15)
				)
				(justify left bottom)
				(hide yes)
			)
		)
		(property "Footprint" "antmicro-footprints:D_SOD-123F"
			(at 86.36 217.17 0)
			(effects
				(font
					(size 1.27 1.27)
					(thickness 0.15)
				)
				(justify left bottom)
				(hide yes)
			)
		)
		(property "Datasheet" "https://assets.nexperia.com/documents/data-sheet/PTVSXS1UR_SER.pdf"
			(at 83.82 217.17 0)
			(effects
				(font
					(size 1.27 1.27)
					(thickness 0.15)
				)
				(justify left bottom)
				(hide yes)
			)
		)
		(property "Description" ""
			(at 96.52 195.58 0)
			(effects
				(font
					(size 1.27 1.27)
				)
				(hide yes)
			)
		)
		(property "MPN" "PTVS58VS1UR,115"
			(at 93.98 199.39 90)
			(effects
				(font
					(size 1.27 1.27)
					(thickness 0.15)
				)
				(justify right)
			)
		)
		(property "Manufacturer" "Nexperia"
			(at 78.74 217.17 0)
			(effects
				(font
					(size 1.27 1.27)
					(thickness 0.15)
				)
				(justify left bottom)
				(hide yes)
			)
		)
		(property "Author" "Antmicro"
			(at 76.2 217.17 0)
			(effects
				(font
					(size 1.27 1.27)
					(thickness 0.15)
				)
				(justify left bottom)
				(hide yes)
			)
		)
		(property "License" "Apache-2.0"
			(at 73.66 217.17 0)
			(effects
				(font
					(size 1.27 1.27)
					(thickness 0.15)
				)
				(justify left bottom)
				(hide yes)
			)
		)
		(pin "1"
		)
		(pin "2"
		)
		(instances
			(project "jetson-orin-baseboard"
				(path ""
					(reference "D14")
					(unit 1)
				)
			)
		)
	)
	(symbol
		(lib_id "antmicroResistors0402:R_200R_0402")
		(at 220.98 92.71 270)
		(mirror x)
		(unit 1)
		(exclude_from_sim no)
		(in_bom yes)
		(on_board yes)
		(dnp no)
		(fields_autoplaced yes)
		(property "Reference" "R147"
			(at 223.52 88.9 90)
			(effects
				(font
					(size 1.27 1.27)
				)
				(justify left)
			)
		)
		(property "Value" "R_200R_0402"
			(at 208.28 72.39 0)
			(effects
				(font
					(size 1.27 1.27)
					(thickness 0.15)
				)
				(justify left bottom)
				(hide yes)
			)
		)
		(property "Footprint" "antmicro-footprints:R_0402_1005Metric"
			(at 205.74 72.39 0)
			(effects
				(font
					(size 1.27 1.27)
					(thickness 0.15)
				)
				(justify left bottom)
				(hide yes)
			)
		)
		(property "Datasheet" "https://www.bourns.com/docs/product-datasheets/cr.pdf"
			(at 203.2 72.39 0)
			(effects
				(font
					(size 1.27 1.27)
					(thickness 0.15)
				)
				(justify left bottom)
				(hide yes)
			)
		)
		(property "Description" ""
			(at 220.98 92.71 0)
			(effects
				(font
					(size 1.27 1.27)
				)
				(hide yes)
			)
		)
		(property "Manufacturer" "Bourns"
			(at 198.12 72.39 0)
			(effects
				(font
					(size 1.27 1.27)
					(thickness 0.15)
				)
				(justify left bottom)
				(hide yes)
			)
		)
		(property "MPN" "CR0402-FX-2000GLF"
			(at 200.66 72.39 0)
			(effects
				(font
					(size 1.27 1.27)
					(thickness 0.15)
				)
				(justify left bottom)
				(hide yes)
			)
		)
		(property "Val" "200R"
			(at 223.52 91.44 90)
			(effects
				(font
					(size 1.27 1.27)
					(thickness 0.15)
				)
				(justify left)
			)
		)
		(property "License" "Apache-2.0"
			(at 195.58 72.39 0)
			(effects
				(font
					(size 1.27 1.27)
					(thickness 0.15)
				)
				(justify left bottom)
				(hide yes)
			)
		)
		(property "Author" "Antmicro"
			(at 193.04 72.39 0)
			(effects
				(font
					(size 1.27 1.27)
					(thickness 0.15)
				)
				(justify left bottom)
				(hide yes)
			)
		)
		(property "Tolerance" "1%"
			(at 210.82 72.39 0)
			(effects
				(font
					(size 1.27 1.27)
				)
				(justify left bottom)
				(hide yes)
			)
		)
		(pin "1"
		)
		(pin "2"
		)
		(instances
			(project "jetson-orin-baseboard"
				(path ""
					(reference "R147")
					(unit 1)
				)
			)
		)
	)
	(symbol
		(lib_id "antmicroLEDIndicationDiscrete:LED_G_0603_LTST-C190GKT")
		(at 241.3 215.9 270)
		(mirror x)
		(unit 1)
		(exclude_from_sim no)
		(in_bom yes)
		(on_board yes)
		(dnp no)
		(property "Reference" "D15"
			(at 244.475 212.09 90)
			(effects
				(font
					(size 1.27 1.27)
				)
				(justify left)
			)
		)
		(property "Value" "LED_G_0603_LTST-C190GKT"
			(at 233.68 193.04 0)
			(effects
				(font
					(size 1.27 1.27)
					(thickness 0.15)
				)
				(justify left bottom)
				(hide yes)
			)
		)
		(property "Footprint" "antmicro-footprints:LED_0603_1608Metric_G"
			(at 231.14 193.04 0)
			(effects
				(font
					(size 1.27 1.27)
					(thickness 0.15)
				)
				(justify left bottom)
				(hide yes)
			)
		)
		(property "Datasheet" "https://media.digikey.com/pdf/Data%20Sheets/Lite-On%20PDFs/LTST-C190GKT.pdf"
			(at 228.6 193.04 0)
			(effects
				(font
					(size 1.27 1.27)
					(thickness 0.15)
				)
				(justify left bottom)
				(hide yes)
			)
		)
		(property "Description" ""
			(at 241.3 215.9 0)
			(effects
				(font
					(size 1.27 1.27)
				)
				(hide yes)
			)
		)
		(property "MPN" "LTST-C190GKT"
			(at 226.06 193.04 0)
			(effects
				(font
					(size 1.27 1.27)
					(thickness 0.15)
				)
				(justify left bottom)
				(hide yes)
			)
		)
		(property "Manufacturer" "Lite-On"
			(at 223.52 193.04 0)
			(effects
				(font
					(size 1.27 1.27)
					(thickness 0.15)
				)
				(justify left bottom)
				(hide yes)
			)
		)
		(property "Author" "Antmicro"
			(at 220.98 193.04 0)
			(effects
				(font
					(size 1.27 1.27)
					(thickness 0.15)
				)
				(justify left bottom)
				(hide yes)
			)
		)
		(property "License" "Apache-2.0"
			(at 218.44 193.04 0)
			(effects
				(font
					(size 1.27 1.27)
					(thickness 0.15)
				)
				(justify left bottom)
				(hide yes)
			)
		)
		(property "Color" "Green"
			(at 244.475 214.63 90)
			(effects
				(font
					(size 1.27 1.27)
				)
				(justify left)
			)
		)
		(pin "1"
		)
		(pin "2"
		)
		(instances
			(project "jetson-orin-baseboard"
				(path ""
					(reference "D15")
					(unit 1)
				)
			)
		)
	)
)
